(kicad_sch
	(version 20231120)
	(generator "eeschema")
	(generator_version "8.0")
	(paper "A3")
	(title_block
		(title "Jetson Orin Baseboard")
		(date "2025-03-12")
		(rev "1.3.4")
		(company "Antmicro Ltd")
		(comment 1 "www.antmicro.com")
	)
	(junction
		(at 213.36 90.17)
		(diameter 0)
		(color 0 0 0 0)
	)
	(junction
		(at 273.05 147.32)
		(diameter 0)
		(color 0 0 0 0)
	)
	(junction
		(at 288.29 149.86)
		(diameter 0)
		(color 0 0 0 0)
	)
	(junction
		(at 309.88 87.63)
		(diameter 0)
		(color 0 0 0 0)
	)
	(junction
		(at 245.11 177.8)
		(diameter 0)
		(color 0 0 0 0)
	)
	(junction
		(at 340.36 78.74)
		(diameter 0)
		(color 0 0 0 0)
	)
	(junction
		(at 325.12 69.85)
		(diameter 0)
		(color 0 0 0 0)
	)
	(junction
		(at 287.02 87.63)
		(diameter 0)
		(color 0 0 0 0)
	)
	(junction
		(at 207.01 92.71)
		(diameter 0)
		(color 0 0 0 0)
	)
	(junction
		(at 270.51 137.16)
		(diameter 0)
		(color 0 0 0 0)
	)
	(junction
		(at 138.43 191.77)
		(diameter 0)
		(color 0 0 0 0)
	)
	(junction
		(at 278.13 87.63)
		(diameter 0)
		(color 0 0 0 0)
	)
	(junction
		(at 288.29 195.58)
		(diameter 0)
		(color 0 0 0 0)
	)
	(junction
		(at 269.24 165.1)
		(diameter 0)
		(color 0 0 0 0)
	)
	(junction
		(at 275.59 149.86)
		(diameter 0)
		(color 0 0 0 0)
	)
	(junction
		(at 242.57 180.34)
		(diameter 0)
		(color 0 0 0 0)
	)
	(junction
		(at 81.28 181.61)
		(diameter 0)
		(color 0 0 0 0)
	)
	(junction
		(at 271.78 162.56)
		(diameter 0)
		(color 0 0 0 0)
	)
	(junction
		(at 113.03 142.24)
		(diameter 0)
		(color 0 0 0 0)
	)
	(junction
		(at 129.54 101.6)
		(diameter 0)
		(color 0 0 0 0)
	)
	(junction
		(at 226.06 74.93)
		(diameter 0)
		(color 0 0 0 0)
	)
	(junction
		(at 290.83 87.63)
		(diameter 0)
		(color 0 0 0 0)
	)
	(junction
		(at 207.01 102.87)
		(diameter 0)
		(color 0 0 0 0)
	)
	(junction
		(at 247.65 172.72)
		(diameter 0)
		(color 0 0 0 0)
	)
	(junction
		(at 207.01 121.92)
		(diameter 0)
		(color 0 0 0 0)
	)
	(junction
		(at 250.19 170.18)
		(diameter 0)
		(color 0 0 0 0)
	)
	(junction
		(at 204.47 77.47)
		(diameter 0)
		(color 0 0 0 0)
	)
	(junction
		(at 151.13 101.6)
		(diameter 0)
		(color 0 0 0 0)
	)
	(junction
		(at 274.32 157.48)
		(diameter 0)
		(color 0 0 0 0)
	)
	(junction
		(at 142.24 101.6)
		(diameter 0)
		(color 0 0 0 0)
	)
	(junction
		(at 287.02 129.54)
		(diameter 0)
		(color 0 0 0 0)
	)
	(junction
		(at 276.86 154.94)
		(diameter 0)
		(color 0 0 0 0)
	)
	(junction
		(at 345.44 78.74)
		(diameter 0)
		(color 0 0 0 0)
	)
	(junction
		(at 287.02 147.32)
		(diameter 0)
		(color 0 0 0 0)
	)
	(junction
		(at 267.97 87.63)
		(diameter 0)
		(color 0 0 0 0)
	)
	(junction
		(at 113.03 124.46)
		(diameter 0)
		(color 0 0 0 0)
	)
	(junction
		(at 355.6 69.85)
		(diameter 0)
		(color 0 0 0 0)
	)
	(junction
		(at 228.6 92.71)
		(diameter 0)
		(color 0 0 0 0)
	)
	(junction
		(at 254 97.79)
		(diameter 0)
		(color 0 0 0 0)
	)
	(junction
		(at 278.13 134.62)
		(diameter 0)
		(color 0 0 0 0)
	)
	(junction
		(at 204.47 92.71)
		(diameter 0)
		(color 0 0 0 0)
	)
	(junction
		(at 199.39 124.46)
		(diameter 0)
		(color 0 0 0 0)
	)
	(no_connect
		(at 289.56 187.96)
	)
	(no_connect
		(at 289.56 185.42)
	)
	(wire
		(pts
			(xy 124.46 154.94) (xy 148.59 154.94)
		)
		(stroke
			(width 0)
			(type default)
		)
	)
	(wire
		(pts
			(xy 335.28 78.74) (xy 340.36 78.74)
		)
		(stroke
			(width 0)
			(type default)
		)
	)
	(wire
		(pts
			(xy 151.13 100.33) (xy 151.13 101.6)
		)
		(stroke
			(width 0)
			(type default)
		)
	)
	(wire
		(pts
			(xy 288.29 193.04) (xy 289.56 193.04)
		)
		(stroke
			(width 0)
			(type default)
		)
	)
	(wire
		(pts
			(xy 124.46 175.26) (xy 148.59 175.26)
		)
		(stroke
			(width 0)
			(type default)
		)
	)
	(wire
		(pts
			(xy 113.03 124.46) (xy 121.92 124.46)
		)
		(stroke
			(width 0)
			(type default)
		)
	)
	(wire
		(pts
			(xy 176.53 124.46) (xy 199.39 124.46)
		)
		(stroke
			(width 0)
			(type default)
		)
	)
	(wire
		(pts
			(xy 204.47 76.2) (xy 204.47 77.47)
		)
		(stroke
			(width 0)
			(type default)
		)
	)
	(wire
		(pts
			(xy 147.32 182.88) (xy 147.32 181.61)
		)
		(stroke
			(width 0)
			(type default)
		)
	)
	(wire
		(pts
			(xy 287.02 129.54) (xy 289.56 129.54)
		)
		(stroke
			(width 0)
			(type default)
		)
	)
	(wire
		(pts
			(xy 245.11 177.8) (xy 245.11 185.42)
		)
		(stroke
			(width 0)
			(type default)
		)
	)
	(wire
		(pts
			(xy 204.47 92.71) (xy 207.01 92.71)
		)
		(stroke
			(width 0)
			(type default)
		)
	)
	(wire
		(pts
			(xy 148.59 121.92) (xy 137.16 121.92)
		)
		(stroke
			(width 0)
			(type default)
		)
	)
	(wire
		(pts
			(xy 105.41 162.56) (xy 100.33 162.56)
		)
		(stroke
			(width 0)
			(type default)
		)
	)
	(wire
		(pts
			(xy 132.08 191.77) (xy 138.43 191.77)
		)
		(stroke
			(width 0)
			(type default)
		)
	)
	(wire
		(pts
			(xy 113.03 177.8) (xy 119.38 177.8)
		)
		(stroke
			(width 0)
			(type default)
		)
	)
	(wire
		(pts
			(xy 250.19 92.71) (xy 251.46 92.71)
		)
		(stroke
			(width 0)
			(type default)
		)
	)
	(wire
		(pts
			(xy 219.71 92.71) (xy 228.6 92.71)
		)
		(stroke
			(width 0)
			(type default)
		)
	)
	(wire
		(pts
			(xy 233.68 184.15) (xy 240.03 184.15)
		)
		(stroke
			(width 0)
			(type default)
		)
	)
	(wire
		(pts
			(xy 325.12 78.74) (xy 330.2 78.74)
		)
		(stroke
			(width 0)
			(type default)
		)
	)
	(wire
		(pts
			(xy 124.46 162.56) (xy 148.59 162.56)
		)
		(stroke
			(width 0)
			(type default)
		)
	)
	(wire
		(pts
			(xy 288.29 195.58) (xy 288.29 193.04)
		)
		(stroke
			(width 0)
			(type default)
		)
	)
	(wire
		(pts
			(xy 176.53 154.94) (xy 276.86 154.94)
		)
		(stroke
			(width 0)
			(type default)
		)
	)
	(wire
		(pts
			(xy 148.59 134.62) (xy 121.92 134.62)
		)
		(stroke
			(width 0)
			(type default)
		)
	)
	(wire
		(pts
			(xy 233.68 87.63) (xy 233.68 74.93)
		)
		(stroke
			(width 0)
			(type default)
		)
	)
	(wire
		(pts
			(xy 226.06 74.93) (xy 233.68 74.93)
		)
		(stroke
			(width 0)
			(type default)
		)
	)
	(wire
		(pts
			(xy 107.95 162.56) (xy 105.41 165.1)
		)
		(stroke
			(width 0)
			(type default)
		)
	)
	(wire
		(pts
			(xy 309.88 93.98) (xy 309.88 95.25)
		)
		(stroke
			(width 0)
			(type default)
		)
	)
	(wire
		(pts
			(xy 289.56 142.24) (xy 287.02 142.24)
		)
		(stroke
			(width 0)
			(type default)
		)
	)
	(wire
		(pts
			(xy 240.03 184.15) (xy 240.03 185.42)
		)
		(stroke
			(width 0)
			(type default)
		)
	)
	(polyline
		(pts
			(xy 323.85 58.42) (xy 323.85 92.71)
		)
		(stroke
			(width 0)
			(type default)
		)
	)
	(wire
		(pts
			(xy 207.01 162.56) (xy 271.78 162.56)
		)
		(stroke
			(width 0)
			(type default)
		)
	)
	(wire
		(pts
			(xy 142.24 107.95) (xy 142.24 109.22)
		)
		(stroke
			(width 0)
			(type default)
		)
	)
	(polyline
		(pts
			(xy 72.39 123.19) (xy 72.39 134.62)
		)
		(stroke
			(width 0)
			(type default)
		)
	)
	(wire
		(pts
			(xy 176.53 121.92) (xy 207.01 121.92)
		)
		(stroke
			(width 0)
			(type default)
		)
	)
	(wire
		(pts
			(xy 113.03 124.46) (xy 113.03 127)
		)
		(stroke
			(width 0)
			(type default)
		)
	)
	(wire
		(pts
			(xy 176.53 119.38) (xy 189.23 119.38)
		)
		(stroke
			(width 0)
			(type default)
		)
	)
	(wire
		(pts
			(xy 195.58 147.32) (xy 273.05 147.32)
		)
		(stroke
			(width 0)
			(type default)
		)
	)
	(wire
		(pts
			(xy 129.54 101.6) (xy 129.54 102.87)
		)
		(stroke
			(width 0)
			(type default)
		)
	)
	(wire
		(pts
			(xy 274.32 157.48) (xy 281.94 157.48)
		)
		(stroke
			(width 0)
			(type default)
		)
	)
	(wire
		(pts
			(xy 250.19 87.63) (xy 267.97 87.63)
		)
		(stroke
			(width 0)
			(type default)
		)
	)
	(wire
		(pts
			(xy 210.82 180.34) (xy 242.57 180.34)
		)
		(stroke
			(width 0)
			(type default)
		)
	)
	(wire
		(pts
			(xy 113.03 142.24) (xy 120.65 142.24)
		)
		(stroke
			(width 0)
			(type default)
		)
	)
	(wire
		(pts
			(xy 267.97 121.92) (xy 267.97 123.19)
		)
		(stroke
			(width 0)
			(type default)
		)
	)
	(wire
		(pts
			(xy 275.59 121.92) (xy 275.59 149.86)
		)
		(stroke
			(width 0)
			(type default)
		)
	)
	(wire
		(pts
			(xy 281.94 172.72) (xy 284.48 170.18)
		)
		(stroke
			(width 0)
			(type default)
		)
	)
	(wire
		(pts
			(xy 278.13 87.63) (xy 278.13 88.9)
		)
		(stroke
			(width 0)
			(type default)
		)
	)
	(wire
		(pts
			(xy 274.32 157.48) (xy 274.32 185.42)
		)
		(stroke
			(width 0)
			(type default)
		)
	)
	(wire
		(pts
			(xy 335.28 69.85) (xy 355.6 69.85)
		)
		(stroke
			(width 0)
			(type default)
		)
	)
	(wire
		(pts
			(xy 267.97 87.63) (xy 267.97 88.9)
		)
		(stroke
			(width 0)
			(type default)
		)
	)
	(wire
		(pts
			(xy 81.28 180.34) (xy 81.28 181.61)
		)
		(stroke
			(width 0)
			(type default)
		)
	)
	(wire
		(pts
			(xy 204.47 77.47) (xy 204.47 78.74)
		)
		(stroke
			(width 0)
			(type default)
		)
	)
	(wire
		(pts
			(xy 250.19 170.18) (xy 250.19 185.42)
		)
		(stroke
			(width 0)
			(type default)
		)
	)
	(wire
		(pts
			(xy 287.02 142.24) (xy 287.02 147.32)
		)
		(stroke
			(width 0)
			(type default)
		)
	)
	(wire
		(pts
			(xy 228.6 92.71) (xy 228.6 95.25)
		)
		(stroke
			(width 0)
			(type default)
		)
	)
	(wire
		(pts
			(xy 195.58 149.86) (xy 275.59 149.86)
		)
		(stroke
			(width 0)
			(type default)
		)
	)
	(wire
		(pts
			(xy 355.6 81.28) (xy 355.6 87.63)
		)
		(stroke
			(width 0)
			(type default)
		)
	)
	(wire
		(pts
			(xy 278.13 87.63) (xy 287.02 87.63)
		)
		(stroke
			(width 0)
			(type default)
		)
	)
	(wire
		(pts
			(xy 121.92 132.08) (xy 121.92 134.62)
		)
		(stroke
			(width 0)
			(type default)
		)
	)
	(polyline
		(pts
			(xy 120.65 134.62) (xy 120.65 123.19)
		)
		(stroke
			(width 0)
			(type default)
		)
	)
	(wire
		(pts
			(xy 148.59 119.38) (xy 139.7 119.38)
		)
		(stroke
			(width 0)
			(type default)
		)
	)
	(wire
		(pts
			(xy 199.39 107.95) (xy 199.39 109.22)
		)
		(stroke
			(width 0)
			(type default)
		)
	)
	(wire
		(pts
			(xy 204.47 83.82) (xy 204.47 92.71)
		)
		(stroke
			(width 0)
			(type default)
		)
	)
	(wire
		(pts
			(xy 271.78 162.56) (xy 271.78 185.42)
		)
		(stroke
			(width 0)
			(type default)
		)
	)
	(wire
		(pts
			(xy 107.95 154.94) (xy 119.38 154.94)
		)
		(stroke
			(width 0)
			(type default)
		)
	)
	(wire
		(pts
			(xy 254 90.17) (xy 254 91.44)
		)
		(stroke
			(width 0)
			(type default)
		)
	)
	(wire
		(pts
			(xy 139.7 101.6) (xy 142.24 101.6)
		)
		(stroke
			(width 0)
			(type default)
		)
	)
	(wire
		(pts
			(xy 107.95 154.94) (xy 105.41 157.48)
		)
		(stroke
			(width 0)
			(type default)
		)
	)
	(wire
		(pts
			(xy 254 96.52) (xy 254 97.79)
		)
		(stroke
			(width 0)
			(type default)
		)
	)
	(wire
		(pts
			(xy 284.48 147.32) (xy 287.02 147.32)
		)
		(stroke
			(width 0)
			(type default)
		)
	)
	(wire
		(pts
			(xy 290.83 93.98) (xy 290.83 95.25)
		)
		(stroke
			(width 0)
			(type default)
		)
	)
	(wire
		(pts
			(xy 210.82 165.1) (xy 269.24 165.1)
		)
		(stroke
			(width 0)
			(type default)
		)
	)
	(wire
		(pts
			(xy 284.48 154.94) (xy 289.56 154.94)
		)
		(stroke
			(width 0)
			(type default)
		)
	)
	(wire
		(pts
			(xy 228.6 92.71) (xy 234.95 92.71)
		)
		(stroke
			(width 0)
			(type default)
		)
	)
	(wire
		(pts
			(xy 250.19 90.17) (xy 254 90.17)
		)
		(stroke
			(width 0)
			(type default)
		)
	)
	(wire
		(pts
			(xy 254 97.79) (xy 254 99.06)
		)
		(stroke
			(width 0)
			(type default)
		)
	)
	(wire
		(pts
			(xy 288.29 144.78) (xy 288.29 149.86)
		)
		(stroke
			(width 0)
			(type default)
		)
	)
	(wire
		(pts
			(xy 207.01 102.87) (xy 207.01 121.92)
		)
		(stroke
			(width 0)
			(type default)
		)
	)
	(wire
		(pts
			(xy 271.78 162.56) (xy 289.56 162.56)
		)
		(stroke
			(width 0)
			(type default)
		)
	)
	(wire
		(pts
			(xy 129.54 100.33) (xy 129.54 101.6)
		)
		(stroke
			(width 0)
			(type default)
		)
	)
	(wire
		(pts
			(xy 281.94 170.18) (xy 284.48 172.72)
		)
		(stroke
			(width 0)
			(type default)
		)
	)
	(wire
		(pts
			(xy 284.48 172.72) (xy 289.56 172.72)
		)
		(stroke
			(width 0)
			(type default)
		)
	)
	(wire
		(pts
			(xy 176.53 165.1) (xy 205.74 165.1)
		)
		(stroke
			(width 0)
			(type default)
		)
	)
	(wire
		(pts
			(xy 270.51 121.92) (xy 270.51 137.16)
		)
		(stroke
			(width 0)
			(type default)
		)
	)
	(wire
		(pts
			(xy 189.23 107.95) (xy 189.23 109.22)
		)
		(stroke
			(width 0)
			(type default)
		)
	)
	(polyline
		(pts
			(xy 323.85 92.71) (xy 341.63 92.71)
		)
		(stroke
			(width 0)
			(type default)
		)
	)
	(wire
		(pts
			(xy 105.41 162.56) (xy 107.95 165.1)
		)
		(stroke
			(width 0)
			(type default)
		)
	)
	(wire
		(pts
			(xy 273.05 121.92) (xy 273.05 147.32)
		)
		(stroke
			(width 0)
			(type default)
		)
	)
	(wire
		(pts
			(xy 287.02 147.32) (xy 289.56 147.32)
		)
		(stroke
			(width 0)
			(type default)
		)
	)
	(wire
		(pts
			(xy 309.88 87.63) (xy 309.88 88.9)
		)
		(stroke
			(width 0)
			(type default)
		)
	)
	(wire
		(pts
			(xy 113.03 139.7) (xy 120.65 139.7)
		)
		(stroke
			(width 0)
			(type default)
		)
	)
	(wire
		(pts
			(xy 213.36 77.47) (xy 213.36 78.74)
		)
		(stroke
			(width 0)
			(type default)
		)
	)
	(wire
		(pts
			(xy 345.44 78.74) (xy 345.44 81.28)
		)
		(stroke
			(width 0)
			(type default)
		)
	)
	(wire
		(pts
			(xy 284.48 149.86) (xy 288.29 149.86)
		)
		(stroke
			(width 0)
			(type default)
		)
	)
	(wire
		(pts
			(xy 204.47 77.47) (xy 213.36 77.47)
		)
		(stroke
			(width 0)
			(type default)
		)
	)
	(wire
		(pts
			(xy 325.12 69.85) (xy 330.2 69.85)
		)
		(stroke
			(width 0)
			(type default)
		)
	)
	(wire
		(pts
			(xy 242.57 180.34) (xy 242.57 185.42)
		)
		(stroke
			(width 0)
			(type default)
		)
	)
	(wire
		(pts
			(xy 269.24 165.1) (xy 289.56 165.1)
		)
		(stroke
			(width 0)
			(type default)
		)
	)
	(polyline
		(pts
			(xy 72.39 123.19) (xy 120.65 123.19)
		)
		(stroke
			(width 0)
			(type default)
		)
	)
	(wire
		(pts
			(xy 124.46 177.8) (xy 148.59 177.8)
		)
		(stroke
			(width 0)
			(type default)
		)
	)
	(wire
		(pts
			(xy 309.88 100.33) (xy 309.88 101.6)
		)
		(stroke
			(width 0)
			(type default)
		)
	)
	(wire
		(pts
			(xy 278.13 121.92) (xy 278.13 134.62)
		)
		(stroke
			(width 0)
			(type default)
		)
	)
	(wire
		(pts
			(xy 176.53 170.18) (xy 250.19 170.18)
		)
		(stroke
			(width 0)
			(type default)
		)
	)
	(wire
		(pts
			(xy 290.83 88.9) (xy 290.83 87.63)
		)
		(stroke
			(width 0)
			(type default)
		)
	)
	(wire
		(pts
			(xy 284.48 170.18) (xy 289.56 170.18)
		)
		(stroke
			(width 0)
			(type default)
		)
	)
	(wire
		(pts
			(xy 242.57 180.34) (xy 289.56 180.34)
		)
		(stroke
			(width 0)
			(type default)
		)
	)
	(wire
		(pts
			(xy 139.7 119.38) (xy 139.7 101.6)
		)
		(stroke
			(width 0)
			(type default)
		)
	)
	(wire
		(pts
			(xy 281.94 154.94) (xy 284.48 157.48)
		)
		(stroke
			(width 0)
			(type default)
		)
	)
	(wire
		(pts
			(xy 124.46 157.48) (xy 148.59 157.48)
		)
		(stroke
			(width 0)
			(type default)
		)
	)
	(wire
		(pts
			(xy 176.53 180.34) (xy 205.74 180.34)
		)
		(stroke
			(width 0)
			(type default)
		)
	)
	(wire
		(pts
			(xy 81.28 187.96) (xy 81.28 189.23)
		)
		(stroke
			(width 0)
			(type default)
		)
	)
	(wire
		(pts
			(xy 176.53 162.56) (xy 201.93 162.56)
		)
		(stroke
			(width 0)
			(type default)
		)
	)
	(wire
		(pts
			(xy 121.92 124.46) (xy 121.92 127)
		)
		(stroke
			(width 0)
			(type default)
		)
	)
	(wire
		(pts
			(xy 288.29 149.86) (xy 289.56 149.86)
		)
		(stroke
			(width 0)
			(type default)
		)
	)
	(wire
		(pts
			(xy 176.53 137.16) (xy 270.51 137.16)
		)
		(stroke
			(width 0)
			(type default)
		)
	)
	(wire
		(pts
			(xy 290.83 87.63) (xy 309.88 87.63)
		)
		(stroke
			(width 0)
			(type default)
		)
	)
	(wire
		(pts
			(xy 88.9 170.18) (xy 88.9 181.61)
		)
		(stroke
			(width 0)
			(type default)
		)
	)
	(wire
		(pts
			(xy 142.24 101.6) (xy 142.24 102.87)
		)
		(stroke
			(width 0)
			(type default)
		)
	)
	(wire
		(pts
			(xy 107.95 165.1) (xy 119.38 165.1)
		)
		(stroke
			(width 0)
			(type default)
		)
	)
	(wire
		(pts
			(xy 267.97 87.63) (xy 278.13 87.63)
		)
		(stroke
			(width 0)
			(type default)
		)
	)
	(wire
		(pts
			(xy 340.36 78.74) (xy 345.44 78.74)
		)
		(stroke
			(width 0)
			(type default)
		)
	)
	(wire
		(pts
			(xy 213.36 83.82) (xy 213.36 90.17)
		)
		(stroke
			(width 0)
			(type default)
		)
	)
	(wire
		(pts
			(xy 273.05 147.32) (xy 281.94 147.32)
		)
		(stroke
			(width 0)
			(type default)
		)
	)
	(wire
		(pts
			(xy 278.13 93.98) (xy 278.13 95.25)
		)
		(stroke
			(width 0)
			(type default)
		)
	)
	(wire
		(pts
			(xy 287.02 87.63) (xy 290.83 87.63)
		)
		(stroke
			(width 0)
			(type default)
		)
	)
	(wire
		(pts
			(xy 340.36 87.63) (xy 340.36 78.74)
		)
		(stroke
			(width 0)
			(type default)
		)
	)
	(wire
		(pts
			(xy 233.68 87.63) (xy 234.95 87.63)
		)
		(stroke
			(width 0)
			(type default)
		)
	)
	(wire
		(pts
			(xy 289.56 144.78) (xy 288.29 144.78)
		)
		(stroke
			(width 0)
			(type default)
		)
	)
	(wire
		(pts
			(xy 113.03 139.7) (xy 113.03 142.24)
		)
		(stroke
			(width 0)
			(type default)
		)
	)
	(wire
		(pts
			(xy 113.03 172.72) (xy 119.38 172.72)
		)
		(stroke
			(width 0)
			(type default)
		)
	)
	(wire
		(pts
			(xy 360.68 69.85) (xy 355.6 69.85)
		)
		(stroke
			(width 0)
			(type default)
		)
	)
	(wire
		(pts
			(xy 124.46 165.1) (xy 148.59 165.1)
		)
		(stroke
			(width 0)
			(type default)
		)
	)
	(wire
		(pts
			(xy 260.35 186.69) (xy 260.35 184.15)
		)
		(stroke
			(width 0)
			(type default)
		)
	)
	(wire
		(pts
			(xy 81.28 181.61) (xy 88.9 181.61)
		)
		(stroke
			(width 0)
			(type default)
		)
	)
	(wire
		(pts
			(xy 335.28 87.63) (xy 340.36 87.63)
		)
		(stroke
			(width 0)
			(type default)
		)
	)
	(wire
		(pts
			(xy 100.33 157.48) (xy 105.41 157.48)
		)
		(stroke
			(width 0)
			(type default)
		)
	)
	(wire
		(pts
			(xy 207.01 121.92) (xy 212.09 121.92)
		)
		(stroke
			(width 0)
			(type default)
		)
	)
	(wire
		(pts
			(xy 148.59 137.16) (xy 113.03 137.16)
		)
		(stroke
			(width 0)
			(type default)
		)
	)
	(wire
		(pts
			(xy 325.12 69.85) (xy 325.12 78.74)
		)
		(stroke
			(width 0)
			(type default)
		)
	)
	(wire
		(pts
			(xy 147.32 181.61) (xy 148.59 181.61)
		)
		(stroke
			(width 0)
			(type default)
		)
	)
	(polyline
		(pts
			(xy 323.85 58.42) (xy 341.63 58.42)
		)
		(stroke
			(width 0)
			(type default)
		)
	)
	(wire
		(pts
			(xy 345.44 86.36) (xy 345.44 87.63)
		)
		(stroke
			(width 0)
			(type default)
		)
	)
	(polyline
		(pts
			(xy 72.39 134.62) (xy 120.65 134.62)
		)
		(stroke
			(width 0)
			(type default)
		)
	)
	(wire
		(pts
			(xy 228.6 105.41) (xy 228.6 106.68)
		)
		(stroke
			(width 0)
			(type default)
		)
	)
	(wire
		(pts
			(xy 176.53 172.72) (xy 247.65 172.72)
		)
		(stroke
			(width 0)
			(type default)
		)
	)
	(wire
		(pts
			(xy 309.88 87.63) (xy 330.2 87.63)
		)
		(stroke
			(width 0)
			(type default)
		)
	)
	(wire
		(pts
			(xy 199.39 90.17) (xy 213.36 90.17)
		)
		(stroke
			(width 0)
			(type default)
		)
	)
	(wire
		(pts
			(xy 260.35 184.15) (xy 266.7 184.15)
		)
		(stroke
			(width 0)
			(type default)
		)
	)
	(wire
		(pts
			(xy 207.01 92.71) (xy 207.01 95.25)
		)
		(stroke
			(width 0)
			(type default)
		)
	)
	(wire
		(pts
			(xy 151.13 107.95) (xy 151.13 109.22)
		)
		(stroke
			(width 0)
			(type default)
		)
	)
	(wire
		(pts
			(xy 207.01 177.8) (xy 245.11 177.8)
		)
		(stroke
			(width 0)
			(type default)
		)
	)
	(wire
		(pts
			(xy 226.06 73.66) (xy 226.06 74.93)
		)
		(stroke
			(width 0)
			(type default)
		)
	)
	(wire
		(pts
			(xy 129.54 107.95) (xy 129.54 109.22)
		)
		(stroke
			(width 0)
			(type default)
		)
	)
	(wire
		(pts
			(xy 107.95 157.48) (xy 119.38 157.48)
		)
		(stroke
			(width 0)
			(type default)
		)
	)
	(wire
		(pts
			(xy 138.43 189.23) (xy 138.43 191.77)
		)
		(stroke
			(width 0)
			(type default)
		)
	)
	(wire
		(pts
			(xy 247.65 172.72) (xy 281.94 172.72)
		)
		(stroke
			(width 0)
			(type default)
		)
	)
	(wire
		(pts
			(xy 207.01 100.33) (xy 207.01 102.87)
		)
		(stroke
			(width 0)
			(type default)
		)
	)
	(wire
		(pts
			(xy 142.24 101.6) (xy 151.13 101.6)
		)
		(stroke
			(width 0)
			(type default)
		)
	)
	(wire
		(pts
			(xy 176.53 157.48) (xy 274.32 157.48)
		)
		(stroke
			(width 0)
			(type default)
		)
	)
	(wire
		(pts
			(xy 254 97.79) (xy 251.46 97.79)
		)
		(stroke
			(width 0)
			(type default)
		)
	)
	(wire
		(pts
			(xy 226.06 74.93) (xy 226.06 76.2)
		)
		(stroke
			(width 0)
			(type default)
		)
	)
	(wire
		(pts
			(xy 355.6 69.85) (xy 355.6 71.12)
		)
		(stroke
			(width 0)
			(type default)
		)
	)
	(wire
		(pts
			(xy 281.94 149.86) (xy 284.48 147.32)
		)
		(stroke
			(width 0)
			(type default)
		)
	)
	(wire
		(pts
			(xy 176.53 134.62) (xy 278.13 134.62)
		)
		(stroke
			(width 0)
			(type default)
		)
	)
	(wire
		(pts
			(xy 113.03 123.19) (xy 113.03 124.46)
		)
		(stroke
			(width 0)
			(type default)
		)
	)
	(wire
		(pts
			(xy 106.68 194.31) (xy 127 194.31)
		)
		(stroke
			(width 0)
			(type default)
		)
	)
	(wire
		(pts
			(xy 233.68 186.69) (xy 233.68 184.15)
		)
		(stroke
			(width 0)
			(type default)
		)
	)
	(wire
		(pts
			(xy 311.15 69.85) (xy 325.12 69.85)
		)
		(stroke
			(width 0)
			(type default)
		)
	)
	(wire
		(pts
			(xy 266.7 184.15) (xy 266.7 185.42)
		)
		(stroke
			(width 0)
			(type default)
		)
	)
	(wire
		(pts
			(xy 189.23 114.3) (xy 189.23 119.38)
		)
		(stroke
			(width 0)
			(type default)
		)
	)
	(wire
		(pts
			(xy 207.01 92.71) (xy 214.63 92.71)
		)
		(stroke
			(width 0)
			(type default)
		)
	)
	(wire
		(pts
			(xy 100.33 165.1) (xy 105.41 165.1)
		)
		(stroke
			(width 0)
			(type default)
		)
	)
	(wire
		(pts
			(xy 276.86 154.94) (xy 281.94 154.94)
		)
		(stroke
			(width 0)
			(type default)
		)
	)
	(wire
		(pts
			(xy 125.73 142.24) (xy 148.59 142.24)
		)
		(stroke
			(width 0)
			(type default)
		)
	)
	(wire
		(pts
			(xy 284.48 157.48) (xy 289.56 157.48)
		)
		(stroke
			(width 0)
			(type default)
		)
	)
	(wire
		(pts
			(xy 199.39 114.3) (xy 199.39 124.46)
		)
		(stroke
			(width 0)
			(type default)
		)
	)
	(wire
		(pts
			(xy 113.03 142.24) (xy 113.03 143.51)
		)
		(stroke
			(width 0)
			(type default)
		)
	)
	(wire
		(pts
			(xy 267.97 93.98) (xy 267.97 95.25)
		)
		(stroke
			(width 0)
			(type default)
		)
	)
	(wire
		(pts
			(xy 288.29 195.58) (xy 289.56 195.58)
		)
		(stroke
			(width 0)
			(type default)
		)
	)
	(wire
		(pts
			(xy 199.39 124.46) (xy 212.09 124.46)
		)
		(stroke
			(width 0)
			(type default)
		)
	)
	(wire
		(pts
			(xy 105.41 154.94) (xy 100.33 154.94)
		)
		(stroke
			(width 0)
			(type default)
		)
	)
	(wire
		(pts
			(xy 113.03 175.26) (xy 119.38 175.26)
		)
		(stroke
			(width 0)
			(type default)
		)
	)
	(wire
		(pts
			(xy 81.28 181.61) (xy 81.28 182.88)
		)
		(stroke
			(width 0)
			(type default)
		)
	)
	(wire
		(pts
			(xy 105.41 154.94) (xy 107.95 157.48)
		)
		(stroke
			(width 0)
			(type default)
		)
	)
	(wire
		(pts
			(xy 250.19 170.18) (xy 281.94 170.18)
		)
		(stroke
			(width 0)
			(type default)
		)
	)
	(wire
		(pts
			(xy 276.86 154.94) (xy 276.86 185.42)
		)
		(stroke
			(width 0)
			(type default)
		)
	)
	(wire
		(pts
			(xy 281.94 147.32) (xy 284.48 149.86)
		)
		(stroke
			(width 0)
			(type default)
		)
	)
	(wire
		(pts
			(xy 137.16 101.6) (xy 129.54 101.6)
		)
		(stroke
			(width 0)
			(type default)
		)
	)
	(wire
		(pts
			(xy 287.02 85.09) (xy 287.02 87.63)
		)
		(stroke
			(width 0)
			(type default)
		)
	)
	(wire
		(pts
			(xy 213.36 129.54) (xy 287.02 129.54)
		)
		(stroke
			(width 0)
			(type default)
		)
	)
	(wire
		(pts
			(xy 88.9 170.18) (xy 148.59 170.18)
		)
		(stroke
			(width 0)
			(type default)
		)
	)
	(wire
		(pts
			(xy 124.46 172.72) (xy 148.59 172.72)
		)
		(stroke
			(width 0)
			(type default)
		)
	)
	(wire
		(pts
			(xy 207.01 102.87) (xy 222.25 102.87)
		)
		(stroke
			(width 0)
			(type default)
		)
	)
	(wire
		(pts
			(xy 213.36 90.17) (xy 234.95 90.17)
		)
		(stroke
			(width 0)
			(type default)
		)
	)
	(wire
		(pts
			(xy 226.06 81.28) (xy 226.06 83.82)
		)
		(stroke
			(width 0)
			(type default)
		)
	)
	(wire
		(pts
			(xy 200.66 92.71) (xy 204.47 92.71)
		)
		(stroke
			(width 0)
			(type default)
		)
	)
	(wire
		(pts
			(xy 281.94 157.48) (xy 284.48 154.94)
		)
		(stroke
			(width 0)
			(type default)
		)
	)
	(polyline
		(pts
			(xy 341.63 92.71) (xy 341.63 58.42)
		)
		(stroke
			(width 0)
			(type default)
		)
	)
	(wire
		(pts
			(xy 275.59 149.86) (xy 281.94 149.86)
		)
		(stroke
			(width 0)
			(type default)
		)
	)
	(wire
		(pts
			(xy 107.95 162.56) (xy 119.38 162.56)
		)
		(stroke
			(width 0)
			(type default)
		)
	)
	(wire
		(pts
			(xy 270.51 137.16) (xy 289.56 137.16)
		)
		(stroke
			(width 0)
			(type default)
		)
	)
	(wire
		(pts
			(xy 137.16 121.92) (xy 137.16 101.6)
		)
		(stroke
			(width 0)
			(type default)
		)
	)
	(wire
		(pts
			(xy 345.44 78.74) (xy 349.25 78.74)
		)
		(stroke
			(width 0)
			(type default)
		)
	)
	(wire
		(pts
			(xy 247.65 172.72) (xy 247.65 185.42)
		)
		(stroke
			(width 0)
			(type default)
		)
	)
	(wire
		(pts
			(xy 176.53 177.8) (xy 201.93 177.8)
		)
		(stroke
			(width 0)
			(type default)
		)
	)
	(wire
		(pts
			(xy 251.46 92.71) (xy 251.46 97.79)
		)
		(stroke
			(width 0)
			(type default)
		)
	)
	(wire
		(pts
			(xy 176.53 129.54) (xy 208.28 129.54)
		)
		(stroke
			(width 0)
			(type default)
		)
	)
	(wire
		(pts
			(xy 278.13 134.62) (xy 289.56 134.62)
		)
		(stroke
			(width 0)
			(type default)
		)
	)
	(wire
		(pts
			(xy 113.03 132.08) (xy 113.03 137.16)
		)
		(stroke
			(width 0)
			(type default)
		)
	)
	(wire
		(pts
			(xy 138.43 194.31) (xy 138.43 191.77)
		)
		(stroke
			(width 0)
			(type default)
		)
	)
	(wire
		(pts
			(xy 106.68 191.77) (xy 127 191.77)
		)
		(stroke
			(width 0)
			(type default)
		)
	)
	(wire
		(pts
			(xy 132.08 194.31) (xy 138.43 194.31)
		)
		(stroke
			(width 0)
			(type default)
		)
	)
	(wire
		(pts
			(xy 125.73 139.7) (xy 148.59 139.7)
		)
		(stroke
			(width 0)
			(type default)
		)
	)
	(wire
		(pts
			(xy 245.11 177.8) (xy 289.56 177.8)
		)
		(stroke
			(width 0)
			(type default)
		)
	)
	(wire
		(pts
			(xy 269.24 165.1) (xy 269.24 185.42)
		)
		(stroke
			(width 0)
			(type default)
		)
	)
	(wire
		(pts
			(xy 288.29 196.85) (xy 288.29 195.58)
		)
		(stroke
			(width 0)
			(type default)
		)
	)
	(wire
		(pts
			(xy 151.13 101.6) (xy 151.13 102.87)
		)
		(stroke
			(width 0)
			(type default)
		)
	)
	(wire
		(pts
			(xy 287.02 87.63) (xy 287.02 129.54)
		)
		(stroke
			(width 0)
			(type default)
		)
	)
	(wire
		(pts
			(xy 81.28 173.99) (xy 81.28 175.26)
		)
		(stroke
			(width 0)
			(type default)
		)
	)
	(text "Mode\nHIGH - DFP (HOST ONLY)\nLOW  - UFP (DEVICE ONLY)\nDNP  - DRP (DUAL ROLE PORT)\n"
		(exclude_from_sim no)
		(at 72.39 132.715 0)
		(effects
			(font
				(size 1.27 1.27)
			)
			(justify left bottom)
		)
	)
	(text "Enable MUX"
		(exclude_from_sim no)
		(at 99.695 139.7 0)
		(effects
			(font
				(size 1.27 1.27)
			)
			(justify left bottom)
		)
	)
	(text "Both DNP - GPIO Mode\nHIGH - I2C Mode 0x67\nLOW -  I2C Mode 0x47"
		(exclude_from_sim no)
		(at 50.165 184.785 0)
		(effects
			(font
				(size 1.27 1.27)
			)
			(justify left bottom)
		)
	)
	(text "USB-C 1"
		(exclude_from_sim no)
		(at 195.58 58.42 0)
		(effects
			(font
				(size 4 4)
				(thickness 0.8)
				(bold yes)
			)
			(justify left bottom)
		)
	)
	(text "10k - 3A\n500k - 1.5A\nDNP - 900mA"
		(exclude_from_sim no)
		(at 128.905 132.08 0)
		(effects
			(font
				(size 1.27 1.27)
			)
			(justify left bottom)
		)
	)
	(text "LOW: DFP role \nHIGH: NO ATTACH/UFP"
		(exclude_from_sim no)
		(at 222.25 121.92 0)
		(effects
			(font
				(size 1.27 1.27)
			)
			(justify left bottom)
		)
	)
	(text "NOTE:\nPopulate 1/3"
		(exclude_from_sim no)
		(at 325.755 62.865 0)
		(effects
			(font
				(size 1.27 1.27)
			)
			(justify left bottom)
		)
	)
	(text "USBC1"
		(exclude_from_sim no)
		(at 305.435 129.54 0)
		(effects
			(font
				(size 1.27 1.27)
				(thickness 0.254)
				(bold yes)
			)
			(justify left bottom)
		)
	)
	(text "LOW: VCONN OC TRIP \nHIGH: NORMAL OPERATION"
		(exclude_from_sim no)
		(at 222.25 128.27 0)
		(effects
			(font
				(size 1.27 1.27)
			)
			(justify left bottom)
		)
	)
	(text "Enable CC controller"
		(exclude_from_sim no)
		(at 90.805 142.24 0)
		(effects
			(font
				(size 1.27 1.27)
			)
			(justify left bottom)
		)
	)
	(label "USBC1_ISC_SCL"
		(at 132.08 175.26 0)
		(effects
			(font
				(size 1.27 1.27)
			)
			(justify left bottom)
		)
	)
	(label "USBC1_RX1_P"
		(at 177.8 157.48 0)
		(effects
			(font
				(size 1.27 1.27)
			)
			(justify left bottom)
		)
	)
	(label "USBC1_ISET"
		(at 251.46 90.17 0)
		(effects
			(font
				(size 1.27 1.27)
			)
			(justify left bottom)
		)
	)
	(label "USBC1_I2C_SDA"
		(at 132.08 172.72 0)
		(effects
			(font
				(size 1.27 1.27)
			)
			(justify left bottom)
		)
	)
	(label "USBC1_CONN_TX2_P"
		(at 222.25 180.34 0)
		(effects
			(font
				(size 1.27 1.27)
			)
			(justify left bottom)
		)
	)
	(label "USBC1_CONN_TX2_N"
		(at 222.25 177.8 0)
		(effects
			(font
				(size 1.27 1.27)
			)
			(justify left bottom)
		)
	)
	(label "USBC1_FAULT_N"
		(at 177.8 124.46 0)
		(effects
			(font
				(size 1.27 1.27)
			)
			(justify left bottom)
		)
	)
	(label "USBC1_CONN_TX1_N"
		(at 222.25 162.56 0)
		(effects
			(font
				(size 1.27 1.27)
			)
			(justify left bottom)
		)
	)
	(label "~{USBC1_INT}"
		(at 132.08 177.8 0)
		(effects
			(font
				(size 1.27 1.27)
			)
			(justify left bottom)
		)
	)
	(label "USBC1_CONN_TX1_P"
		(at 222.25 165.1 0)
		(effects
			(font
				(size 1.27 1.27)
			)
			(justify left bottom)
		)
	)
	(label "USBC1_PORT"
		(at 132.08 137.16 0)
		(effects
			(font
				(size 1.27 1.27)
			)
			(justify left bottom)
		)
	)
	(label "USBC1_TX2_N"
		(at 177.8 177.8 0)
		(effects
			(font
				(size 1.27 1.27)
			)
			(justify left bottom)
		)
	)
	(label "USBSS1_C_RX_P"
		(at 132.08 157.48 0)
		(effects
			(font
				(size 1.27 1.27)
			)
			(justify left bottom)
		)
	)
	(label "USBC1_TX1_N"
		(at 177.8 162.56 0)
		(effects
			(font
				(size 1.27 1.27)
			)
			(justify left bottom)
		)
	)
	(label "USBSS1_C_TX_N"
		(at 132.08 162.56 0)
		(effects
			(font
				(size 1.27 1.27)
			)
			(justify left bottom)
		)
	)
	(label "USBC1_ISC_SCL"
		(at 106.68 194.31 0)
		(effects
			(font
				(size 1.27 1.27)
			)
			(justify left bottom)
		)
	)
	(label "~{USBC1_EN_MUX}"
		(at 132.08 139.7 0)
		(effects
			(font
				(size 1.27 1.27)
			)
			(justify left bottom)
		)
	)
	(label "USBC1_VBUS_DET"
		(at 177.8 129.54 0)
		(effects
			(font
				(size 1.27 1.27)
			)
			(justify left bottom)
		)
	)
	(label "USBC1_CC2"
		(at 222.25 137.16 0)
		(effects
			(font
				(size 1.27 1.27)
			)
			(justify left bottom)
		)
	)
	(label "USBC1_TX2_P"
		(at 177.8 180.34 0)
		(effects
			(font
				(size 1.27 1.27)
			)
			(justify left bottom)
		)
	)
	(label "USBC1_I_MODE"
		(at 132.08 134.62 0)
		(effects
			(font
				(size 1.27 1.27)
			)
			(justify left bottom)
		)
	)
	(label "USBC1_VBUS"
		(at 251.46 87.63 0)
		(effects
			(font
				(size 1.27 1.27)
			)
			(justify left bottom)
		)
	)
	(label "USBSS1_C_TX_P"
		(at 132.08 165.1 0)
		(effects
			(font
				(size 1.27 1.27)
			)
			(justify left bottom)
		)
	)
	(label "USBC1_TX1_P"
		(at 177.8 165.1 0)
		(effects
			(font
				(size 1.27 1.27)
			)
			(justify left bottom)
		)
	)
	(label "USBC1_ID"
		(at 311.15 69.85 0)
		(effects
			(font
				(size 1.27 1.27)
			)
			(justify left bottom)
		)
	)
	(label "USBC1_I2C_SDA"
		(at 106.68 191.77 0)
		(effects
			(font
				(size 1.27 1.27)
			)
			(justify left bottom)
		)
	)
	(label "USBSS1_C_RX_N"
		(at 132.08 154.94 0)
		(effects
			(font
				(size 1.27 1.27)
			)
			(justify left bottom)
		)
	)
	(label "USBC1_CC1"
		(at 222.25 134.62 0)
		(effects
			(font
				(size 1.27 1.27)
			)
			(justify left bottom)
		)
	)
	(label "~{USBC1_EN_CC}"
		(at 132.08 142.24 0)
		(effects
			(font
				(size 1.27 1.27)
			)
			(justify left bottom)
		)
	)
	(label "USBC1_ADDR"
		(at 132.08 170.18 0)
		(effects
			(font
				(size 1.27 1.27)
			)
			(justify left bottom)
		)
	)
	(label "USBC1_RX1_N"
		(at 177.8 154.94 0)
		(effects
			(font
				(size 1.27 1.27)
			)
			(justify left bottom)
		)
	)
	(label "USBC1_ID"
		(at 177.8 121.92 0)
		(effects
			(font
				(size 1.27 1.27)
			)
			(justify left bottom)
		)
	)
	(label "USBC1_RX2_N"
		(at 177.8 170.18 0)
		(effects
			(font
				(size 1.27 1.27)
			)
			(justify left bottom)
		)
	)
	(label "USBC1_DIR"
		(at 177.8 119.38 0)
		(effects
			(font
				(size 1.27 1.27)
			)
			(justify left bottom)
		)
	)
	(label "USBC1_RX2_P"
		(at 177.8 172.72 0)
		(effects
			(font
				(size 1.27 1.27)
			)
			(justify left bottom)
		)
	)
	(global_label "GPIO010"
		(shape output)
		(at 113.03 177.8 180)
		(effects
			(font
				(size 1.27 1.27)
			)
			(justify right)
		)
		(property "Intersheetrefs" "${INTERSHEET_REFS}"
			(at 91.44 177.8 0)
			(effects
				(font
					(size 1.27 1.27)
				)
				(justify left)
			)
		)
	)
	(global_label "SYS_SCL"
		(shape input)
		(at 113.03 175.26 180)
		(effects
			(font
				(size 1.27 1.27)
			)
			(justify right)
		)
		(property "Intersheetrefs" "${INTERSHEET_REFS}"
			(at 91.44 175.26 0)
			(effects
				(font
					(size 1.27 1.27)
				)
				(justify left)
			)
		)
	)
	(global_label "USBC1_PEN"
		(shape input)
		(at 200.66 92.71 180)
		(effects
			(font
				(size 1.27 1.27)
			)
			(justify right)
		)
		(property "Intersheetrefs" "${INTERSHEET_REFS}"
			(at 186.69 92.71 0)
			(effects
				(font
					(size 1.27 1.27)
				)
				(justify right)
			)
		)
	)
	(global_label "USB_FLASH_ID"
		(shape output)
		(at 360.68 69.85 0)
		(fields_autoplaced yes)
		(effects
			(font
				(size 1.27 1.27)
			)
			(justify left)
		)
		(property "Intersheetrefs" "${INTERSHEET_REFS}"
			(at 376.4583 69.7706 0)
			(effects
				(font
					(size 1.27 1.27)
				)
				(justify left)
			)
		)
	)
	(global_label "USBSS2_TX_P"
		(shape input)
		(at 100.33 165.1 180)
		(effects
			(font
				(size 1.27 1.27)
			)
			(justify right)
		)
		(property "Intersheetrefs" "${INTERSHEET_REFS}"
			(at 81.915 165.1 0)
			(effects
				(font
					(size 1.27 1.27)
				)
				(justify right)
			)
		)
	)
	(global_label "USB0_D_N"
		(shape input)
		(at 195.58 147.32 180)
		(effects
			(font
				(size 1.27 1.27)
			)
			(justify right)
		)
		(property "Intersheetrefs" "${INTERSHEET_REFS}"
			(at 182.245 147.32 0)
			(effects
				(font
					(size 1.27 1.27)
				)
				(justify right)
			)
		)
	)
	(global_label "USBSS2_TX_N"
		(shape input)
		(at 100.33 162.56 180)
		(effects
			(font
				(size 1.27 1.27)
			)
			(justify right)
		)
		(property "Intersheetrefs" "${INTERSHEET_REFS}"
			(at 81.915 162.56 0)
			(effects
				(font
					(size 1.27 1.27)
				)
				(justify right)
			)
		)
	)
	(global_label "USB0_D_P"
		(shape input)
		(at 195.58 149.86 180)
		(effects
			(font
				(size 1.27 1.27)
			)
			(justify right)
		)
		(property "Intersheetrefs" "${INTERSHEET_REFS}"
			(at 182.245 149.86 0)
			(effects
				(font
					(size 1.27 1.27)
				)
				(justify right)
			)
		)
	)
	(global_label "USBSS2_RX_P"
		(shape output)
		(at 100.33 157.48 180)
		(effects
			(font
				(size 1.27 1.27)
			)
			(justify right)
		)
		(property "Intersheetrefs" "${INTERSHEET_REFS}"
			(at 81.28 157.48 0)
			(effects
				(font
					(size 1.1 1.1)
				)
				(justify right)
			)
		)
	)
	(global_label "USBC1_FLG"
		(shape output)
		(at 199.39 90.17 180)
		(effects
			(font
				(size 1.27 1.27)
			)
			(justify right)
		)
		(property "Intersheetrefs" "${INTERSHEET_REFS}"
			(at 185.42 90.17 0)
			(effects
				(font
					(size 1.27 1.27)
				)
				(justify right)
			)
		)
	)
	(global_label "USBSS2_RX_N"
		(shape output)
		(at 100.33 154.94 180)
		(effects
			(font
				(size 1.27 1.27)
			)
			(justify right)
		)
		(property "Intersheetrefs" "${INTERSHEET_REFS}"
			(at 81.28 154.94 0)
			(effects
				(font
					(size 1.1 1.1)
				)
				(justify right)
			)
		)
	)
	(global_label "SYS_SDA"
		(shape bidirectional)
		(at 113.03 172.72 180)
		(effects
			(font
				(size 1.27 1.27)
			)
			(justify right)
		)
		(property "Intersheetrefs" "${INTERSHEET_REFS}"
			(at 91.44 172.72 0)
			(effects
				(font
					(size 1.27 1.27)
				)
				(justify left)
			)
		)
	)
	(symbol
		(lib_id "antmicroInterfaceControllers:HD3SS3220RNH")
		(at 148.59 119.38 0)
		(unit 1)
		(exclude_from_sim no)
		(in_bom yes)
		(on_board yes)
		(dnp no)
		(property "Reference" "U17"
			(at 162.56 113.03 0)
			(effects
				(font
					(size 1.27 1.27)
				)
			)
		)
		(property "Value" "HD3SS3220RNH"
			(at 190.5 127 0)
			(effects
				(font
					(size 1.27 1.27)
					(thickness 0.15)
				)
				(justify left bottom)
				(hide yes)
			)
		)
		(property "Footprint" "antmicro-footprints:WQFN-30-1EP_4.6x2.6mm_P0.4mm"
			(at 190.5 129.54 0)
			(effects
				(font
					(size 1.27 1.27)
					(thickness 0.15)
				)
				(justify left bottom)
				(hide yes)
			)
		)
		(property "Datasheet" "https://www.ti.com/lit/ds/symlink/hd3ss3220.pdf?ts=1663000043694&ref_url=https%253A%252F%252Fwww.google.com%252F"
			(at 190.5 132.08 0)
			(effects
				(font
					(size 1.27 1.27)
					(thickness 0.15)
				)
				(justify left bottom)
				(hide yes)
			)
		)
		(property "Description" ""
			(at 148.59 119.38 0)
			(effects
				(font
					(size 1.27 1.27)
				)
				(hide yes)
			)
		)
		(property "Manufacturer" "Texas Instruments"
			(at 190.5 134.62 0)
			(effects
				(font
					(size 1.27 1.27)
					(thickness 0.15)
				)
				(justify left bottom)
				(hide yes)
			)
		)
		(property "MPN" "HD3SS3220RNHT"
			(at 162.56 115.57 0)
			(effects
				(font
					(size 1.27 1.27)
					(thickness 0.15)
				)
			)
		)
		(property "Author" "Antmicro"
			(at 190.5 139.7 0)
			(effects
				(font
					(size 1.27 1.27)
					(thickness 0.15)
				)
				(justify left bottom)
				(hide yes)
			)
		)
		(property "License" "Apache-2.0"
			(at 190.5 142.24 0)
			(effects
				(font
					(size 1.27 1.27)
					(thickness 0.15)
				)
				(justify left bottom)
				(hide yes)
			)
		)
		(pin "1"
		)
		(pin "10"
		)
		(pin "11"
		)
		(pin "12"
		)
		(pin "13"
		)
		(pin "14"
		)
		(pin "15"
		)
		(pin "16"
		)
		(pin "17"
		)
		(pin "18"
		)
		(pin "19"
		)
		(pin "2"
		)
		(pin "20"
		)
		(pin "21"
		)
		(pin "22"
		)
		(pin "23"
		)
		(pin "24"
		)
		(pin "25"
		)
		(pin "26"
		)
		(pin "27"
		)
		(pin "28"
		)
		(pin "29"
		)
		(pin "3"
		)
		(pin "30"
		)
		(pin "31"
		)
		(pin "4"
		)
		(pin "5"
		)
		(pin "6"
		)
		(pin "7"
		)
		(pin "8"
		)
		(pin "9"
		)
		(instances
			(project "jetson-orin-baseboard"
				(path ""
					(reference "U17")
					(unit 1)
				)
			)
		)
	)
	(symbol
		(lib_id "antmicroResistors0402:R_470R_0402")
		(at 309.88 93.98 90)
		(unit 1)
		(exclude_from_sim no)
		(in_bom yes)
		(on_board yes)
		(dnp no)
		(property "Reference" "R140"
			(at 311.15 90.17 90)
			(effects
				(font
					(size 1.27 1.27)
				)
				(justify right)
			)
		)
		(property "Value" "R_470R_0402"
			(at 322.58 73.66 0)
			(effects
				(font
					(size 1.27 1.27)
					(thickness 0.15)
				)
				(justify left bottom)
				(hide yes)
			)
		)
		(property "Footprint" "antmicro-footprints:R_0402_1005Metric"
			(at 325.12 73.66 0)
			(effects
				(font
					(size 1.27 1.27)
					(thickness 0.15)
				)
				(justify left bottom)
				(hide yes)
			)
		)
		(property "Datasheet" "https://www.bourns.com/docs/product-datasheets/cr.pdf"
			(at 327.66 73.66 0)
			(effects
				(font
					(size 1.27 1.27)
					(thickness 0.15)
				)
				(justify left bottom)
				(hide yes)
			)
		)
		(property "Description" ""
			(at 309.88 93.98 0)
			(effects
				(font
					(size 1.27 1.27)
				)
				(hide yes)
			)
		)
		(property "Manufacturer" "Bourns"
			(at 332.74 73.66 0)
			(effects
				(font
					(size 1.27 1.27)
					(thickness 0.15)
				)
				(justify left bottom)
				(hide yes)
			)
		)
		(property "MPN" "CR0402-FX-4700GLF"
			(at 330.2 73.66 0)
			(effects
				(font
					(size 1.27 1.27)
					(thickness 0.15)
				)
				(justify left bottom)
				(hide yes)
			)
		)
		(property "Val" "470R"
			(at 311.15 92.71 90)
			(effects
				(font
					(size 1.27 1.27)
					(thickness 0.15)
				)
				(justify right)
			)
		)
		(property "License" "Apache-2.0"
			(at 335.28 73.66 0)
			(effects
				(font
					(size 1.27 1.27)
					(thickness 0.15)
				)
				(justify left bottom)
				(hide yes)
			)
		)
		(property "Author" "Antmicro"
			(at 337.82 73.66 0)
			(effects
				(font
					(size 1.27 1.27)
					(thickness 0.15)
				)
				(justify left bottom)
				(hide yes)
			)
		)
		(property "Tolerance" "1%"
			(at 320.04 73.66 0)
			(effects
				(font
					(size 1.27 1.27)
				)
				(justify left bottom)
				(hide yes)
			)
		)
		(pin "1"
		)
		(pin "2"
		)
		(instances
			(project "jetson-orin-baseboard"
				(path ""
					(reference "R140")
					(unit 1)
				)
			)
		)
	)
	(symbol
		(lib_id "antmicroLEDIndicationDiscrete:LED_G_0603_LTST-C190GKT")
		(at 309.88 100.33 90)
		(unit 1)
		(exclude_from_sim no)
		(in_bom yes)
		(on_board yes)
		(dnp no)
		(fields_autoplaced yes)
		(property "Reference" "D11"
			(at 311.785 96.52 90)
			(effects
				(font
					(size 1.27 1.27)
				)
				(justify right)
			)
		)
		(property "Value" "LED_G_0603_LTST-C190GKT"
			(at 317.5 77.47 0)
			(effects
				(font
					(size 1.27 1.27)
					(thickness 0.15)
				)
				(justify left bottom)
				(hide yes)
			)
		)
		(property "Footprint" "antmicro-footprints:LED_0603_1608Metric_G"
			(at 320.04 77.47 0)
			(effects
				(font
					(size 1.27 1.27)
					(thickness 0.15)
				)
				(justify left bottom)
				(hide yes)
			)
		)
		(property "Datasheet" "https://media.digikey.com/pdf/Data%20Sheets/Lite-On%20PDFs/LTST-C190GKT.pdf"
			(at 322.58 77.47 0)
			(effects
				(font
					(size 1.27 1.27)
					(thickness 0.15)
				)
				(justify left bottom)
				(hide yes)
			)
		)
		(property "Description" ""
			(at 309.88 100.33 0)
			(effects
				(font
					(size 1.27 1.27)
				)
				(hide yes)
			)
		)
		(property "MPN" "LTST-C190GKT"
			(at 325.12 77.47 0)
			(effects
				(font
					(size 1.27 1.27)
					(thickness 0.15)
				)
				(justify left bottom)
				(hide yes)
			)
		)
		(property "Manufacturer" "Lite-On"
			(at 327.66 77.47 0)
			(effects
				(font
					(size 1.27 1.27)
					(thickness 0.15)
				)
				(justify left bottom)
				(hide yes)
			)
		)
		(property "Author" "Antmicro"
			(at 330.2 77.47 0)
			(effects
				(font
					(size 1.27 1.27)
					(thickness 0.15)
				)
				(justify left bottom)
				(hide yes)
			)
		)
		(property "License" "Apache-2.0"
			(at 332.74 77.47 0)
			(effects
				(font
					(size 1.27 1.27)
					(thickness 0.15)
				)
				(justify left bottom)
				(hide yes)
			)
		)
		(property "Color" "Green"
			(at 311.785 99.06 90)
			(effects
				(font
					(size 1.27 1.27)
				)
				(justify right)
			)
		)
		(pin "1"
		)
		(pin "2"
		)
		(instances
			(project "jetson-orin-baseboard"
				(path ""
					(reference "D11")
					(unit 1)
				)
			)
		)
	)
	(symbol
		(lib_name "GND_3")
		(lib_id "antmicropower:GND")
		(at 226.06 83.82 0)
		(unit 1)
		(exclude_from_sim no)
		(in_bom yes)
		(on_board yes)
		(dnp no)
		(property "Reference" "#PWR0122"
			(at 226.06 90.17 0)
			(effects
				(font
					(size 1.27 1.27)
				)
				(justify left bottom)
				(hide yes)
			)
		)
		(property "Value" "GND"
			(at 226.06 87.63 0)
			(effects
				(font
					(size 1.27 1.27)
					(thickness 0.15)
				)
			)
		)
		(property "Footprint" ""
			(at 234.95 91.44 0)
			(effects
				(font
					(size 1.27 1.27)
					(thickness 0.15)
				)
				(justify left bottom)
				(hide yes)
			)
		)
		(property "Datasheet" ""
			(at 234.95 96.52 0)
			(effects
				(font
					(size 1.27 1.27)
					(thickness 0.15)
				)
				(justify left bottom)
				(hide yes)
			)
		)
		(property "Description" ""
			(at 226.06 83.82 0)
			(effects
				(font
					(size 1.27 1.27)
				)
				(hide yes)
			)
		)
		(property "Author" "Antmicro"
			(at 234.95 91.44 0)
			(effects
				(font
					(size 1.27 1.27)
					(thickness 0.15)
				)
				(justify left bottom)
				(hide yes)
			)
		)
		(property "License" "Apache-2.0"
			(at 234.95 93.98 0)
			(effects
				(font
					(size 1.27 1.27)
					(thickness 0.15)
				)
				(justify left bottom)
				(hide yes)
			)
		)
		(pin "1"
		)
		(instances
			(project "jetson-orin-baseboard"
				(path ""
					(reference "#PWR0122")
					(unit 1)
				)
			)
		)
	)
	(symbol
		(lib_id "antmicroResistors0402:R_10k_0402")
		(at 335.28 78.74 180)
		(unit 1)
		(exclude_from_sim no)
		(in_bom yes)
		(on_board yes)
		(dnp no)
		(property "Reference" "R24"
			(at 335.28 78.105 0)
			(effects
				(font
					(size 1.27 1.27)
				)
				(justify right top)
			)
		)
		(property "Value" "R_10k_0402"
			(at 314.96 66.04 0)
			(effects
				(font
					(size 1.27 1.27)
					(thickness 0.15)
				)
				(justify left bottom)
				(hide yes)
			)
		)
		(property "Footprint" "antmicro-footprints:R_0402_1005Metric"
			(at 314.96 63.5 0)
			(effects
				(font
					(size 1.27 1.27)
					(thickness 0.15)
				)
				(justify left bottom)
				(hide yes)
			)
		)
		(property "Datasheet" "https://www.bourns.com/docs/product-datasheets/cr.pdf"
			(at 314.96 60.96 0)
			(effects
				(font
					(size 1.27 1.27)
					(thickness 0.15)
				)
				(justify left bottom)
				(hide yes)
			)
		)
		(property "Description" ""
			(at 335.28 78.74 0)
			(effects
				(font
					(size 1.27 1.27)
				)
				(hide yes)
			)
		)
		(property "Manufacturer" "Bourns"
			(at 314.96 55.88 0)
			(effects
				(font
					(size 1.27 1.27)
					(thickness 0.15)
				)
				(justify left bottom)
				(hide yes)
			)
		)
		(property "MPN" "CR0402-FX-1002GLF"
			(at 314.96 58.42 0)
			(effects
				(font
					(size 1.27 1.27)
					(thickness 0.15)
				)
				(justify left bottom)
				(hide yes)
			)
		)
		(property "Val" "10k"
			(at 326.39 78.105 0)
			(effects
				(font
					(size 1.27 1.27)
					(thickness 0.15)
				)
				(justify right top)
			)
		)
		(property "License" "Apache-2.0"
			(at 314.96 53.34 0)
			(effects
				(font
					(size 1.27 1.27)
					(thickness 0.15)
				)
				(justify left bottom)
				(hide yes)
			)
		)
		(property "Author" "Antmicro"
			(at 314.96 50.8 0)
			(effects
				(font
					(size 1.27 1.27)
					(thickness 0.15)
				)
				(justify left bottom)
				(hide yes)
			)
		)
		(property "Tolerance" "1%"
			(at 314.96 68.58 0)
			(effects
				(font
					(size 1.27 1.27)
				)
				(justify left bottom)
				(hide yes)
			)
		)
		(pin "1"
		)
		(pin "2"
		)
		(instances
			(project "jetson-orin-baseboard"
				(path ""
					(reference "R24")
					(unit 1)
				)
			)
		)
	)
	(symbol
		(lib_id "antmicroPMICPowerDistributionSwitchesLoadDrivers:AP22615A_TSOT26")
		(at 234.95 87.63 0)
		(unit 1)
		(exclude_from_sim no)
		(in_bom yes)
		(on_board yes)
		(dnp no)
		(property "Reference" "U18"
			(at 242.57 81.28 0)
			(effects
				(font
					(size 1.27 1.27)
				)
			)
		)
		(property "Value" "AP22615A_TSOT26"
			(at 265.43 92.71 0)
			(effects
				(font
					(size 1.27 1.27)
					(thickness 0.15)
				)
				(justify left bottom)
				(hide yes)
			)
		)
		(property "Footprint" "antmicro-footprints:TSOT23-6"
			(at 265.43 95.25 0)
			(effects
				(font
					(size 1.27 1.27)
					(thickness 0.15)
				)
				(justify left bottom)
				(hide yes)
			)
		)
		(property "Datasheet" "https://www.mouser.com/datasheet/2/115/DIOD_S_A0008958405_1-2543193.pdf"
			(at 265.43 97.79 0)
			(effects
				(font
					(size 1.27 1.27)
					(thickness 0.15)
				)
				(justify left bottom)
				(hide yes)
			)
		)
		(property "Description" ""
			(at 234.95 87.63 0)
			(effects
				(font
					(size 1.27 1.27)
				)
				(hide yes)
			)
		)
		(property "MPN" "AP22615AWU-7"
			(at 242.57 83.82 0)
			(effects
				(font
					(size 1.27 1.27)
					(thickness 0.15)
				)
			)
		)
		(property "Manufacturer" "Diodes Incorporated"
			(at 265.43 102.87 0)
			(effects
				(font
					(size 1.27 1.27)
					(thickness 0.15)
				)
				(justify left bottom)
				(hide yes)
			)
		)
		(property "Author" "Antmicro"
			(at 265.43 105.41 0)
			(effects
				(font
					(size 1.27 1.27)
					(thickness 0.15)
				)
				(justify left bottom)
				(hide yes)
			)
		)
		(property "License" "Apache-2.0"
			(at 265.43 107.95 0)
			(effects
				(font
					(size 1.27 1.27)
					(thickness 0.15)
				)
				(justify left bottom)
				(hide yes)
			)
		)
		(pin "1"
		)
		(pin "2"
		)
		(pin "3"
		)
		(pin "4"
		)
		(pin "5"
		)
		(pin "6"
		)
		(instances
			(project "jetson-orin-baseboard"
				(path ""
					(reference "U18")
					(unit 1)
				)
			)
		)
	)
	(symbol
		(lib_name "GND_3")
		(lib_id "antmicropower:GND")
		(at 278.13 95.25 0)
		(unit 1)
		(exclude_from_sim no)
		(in_bom yes)
		(on_board yes)
		(dnp no)
		(property "Reference" "#PWR0129"
			(at 278.13 101.6 0)
			(effects
				(font
					(size 1.27 1.27)
				)
				(justify left bottom)
				(hide yes)
			)
		)
		(property "Value" "GND"
			(at 278.13 99.06 0)
			(effects
				(font
					(size 1.27 1.27)
					(thickness 0.15)
				)
			)
		)
		(property "Footprint" ""
			(at 287.02 102.87 0)
			(effects
				(font
					(size 1.27 1.27)
					(thickness 0.15)
				)
				(justify left bottom)
				(hide yes)
			)
		)
		(property "Datasheet" ""
			(at 287.02 107.95 0)
			(effects
				(font
					(size 1.27 1.27)
					(thickness 0.15)
				)
				(justify left bottom)
				(hide yes)
			)
		)
		(property "Description" ""
			(at 278.13 95.25 0)
			(effects
				(font
					(size 1.27 1.27)
				)
				(hide yes)
			)
		)
		(property "Author" "Antmicro"
			(at 287.02 102.87 0)
			(effects
				(font
					(size 1.27 1.27)
					(thickness 0.15)
				)
				(justify left bottom)
				(hide yes)
			)
		)
		(property "License" "Apache-2.0"
			(at 287.02 105.41 0)
			(effects
				(font
					(size 1.27 1.27)
					(thickness 0.15)
				)
				(justify left bottom)
				(hide yes)
			)
		)
		(pin "1"
		)
		(instances
			(project "jetson-orin-baseboard"
				(path ""
					(reference "#PWR0129")
					(unit 1)
				)
			)
		)
	)
	(symbol
		(lib_name "GND_3")
		(lib_id "antmicropower:GND")
		(at 142.24 109.22 0)
		(unit 1)
		(exclude_from_sim no)
		(in_bom yes)
		(on_board yes)
		(dnp no)
		(property "Reference" "#PWR0115"
			(at 142.24 115.57 0)
			(effects
				(font
					(size 1.27 1.27)
				)
				(justify left bottom)
				(hide yes)
			)
		)
		(property "Value" "GND"
			(at 142.24 113.03 0)
			(effects
				(font
					(size 1.27 1.27)
					(thickness 0.15)
				)
			)
		)
		(property "Footprint" ""
			(at 151.13 116.84 0)
			(effects
				(font
					(size 1.27 1.27)
					(thickness 0.15)
				)
				(justify left bottom)
				(hide yes)
			)
		)
		(property "Datasheet" ""
			(at 151.13 121.92 0)
			(effects
				(font
					(size 1.27 1.27)
					(thickness 0.15)
				)
				(justify left bottom)
				(hide yes)
			)
		)
		(property "Description" ""
			(at 142.24 109.22 0)
			(effects
				(font
					(size 1.27 1.27)
				)
				(hide yes)
			)
		)
		(property "Author" "Antmicro"
			(at 151.13 116.84 0)
			(effects
				(font
					(size 1.27 1.27)
					(thickness 0.15)
				)
				(justify left bottom)
				(hide yes)
			)
		)
		(property "License" "Apache-2.0"
			(at 151.13 119.38 0)
			(effects
				(font
					(size 1.27 1.27)
					(thickness 0.15)
				)
				(justify left bottom)
				(hide yes)
			)
		)
		(pin "1"
		)
		(instances
			(project "jetson-orin-baseboard"
				(path ""
					(reference "#PWR0115")
					(unit 1)
				)
			)
		)
	)
	(symbol
		(lib_id "antmicroTestPoints:TP_0.75mm_SMD")
		(at 212.09 124.46 0)
		(unit 1)
		(exclude_from_sim no)
		(in_bom no)
		(on_board yes)
		(dnp no)
		(property "Reference" "TP32"
			(at 215.9 124.46 0)
			(effects
				(font
					(size 1.27 1.27)
				)
				(justify left)
			)
		)
		(property "Value" "TP_0.75mm_SMD"
			(at 222.25 128.27 0)
			(effects
				(font
					(size 1.27 1.27)
					(thickness 0.15)
				)
				(justify left bottom)
				(hide yes)
			)
		)
		(property "Footprint" "antmicro-footprints:TP_SMD_0.75mm"
			(at 222.25 130.81 0)
			(effects
				(font
					(size 1.27 1.27)
					(thickness 0.15)
				)
				(justify left bottom)
				(hide yes)
			)
		)
		(property "Datasheet" ""
			(at 229.87 137.16 0)
			(effects
				(font
					(size 1.27 1.27)
					(thickness 0.15)
				)
				(justify left bottom)
				(hide yes)
			)
		)
		(property "Description" ""
			(at 212.09 124.46 0)
			(effects
				(font
					(size 1.27 1.27)
				)
				(hide yes)
			)
		)
		(property "MPN" ""
			(at 222.885 135.89 0)
			(effects
				(font
					(size 1.27 1.27)
					(thickness 0.15)
				)
				(justify left bottom)
				(hide yes)
			)
		)
		(property "Manufacturer" ""
			(at 222.885 130.81 0)
			(effects
				(font
					(size 1.27 1.27)
					(thickness 0.15)
				)
				(justify left bottom)
				(hide yes)
			)
		)
		(property "Author" "Antmicro"
			(at 222.25 133.35 0)
			(effects
				(font
					(size 1.27 1.27)
					(thickness 0.15)
				)
				(justify left bottom)
				(hide yes)
			)
		)
		(property "License" "Apache-2.0"
			(at 222.25 135.89 0)
			(effects
				(font
					(size 1.27 1.27)
					(thickness 0.15)
				)
				(justify left bottom)
				(hide yes)
			)
		)
		(pin "1"
		)
		(instances
			(project "jetson-orin-baseboard"
				(path ""
					(reference "TP32")
					(unit 1)
				)
			)
		)
	)
	(symbol
		(lib_name "+5V_1")
		(lib_id "antmicropower:+5V")
		(at 113.03 123.19 0)
		(unit 1)
		(exclude_from_sim no)
		(in_bom yes)
		(on_board yes)
		(dnp no)
		(property "Reference" "#PWR0110"
			(at 113.03 127 0)
			(effects
				(font
					(size 1.27 1.27)
				)
				(justify left bottom)
				(hide yes)
			)
		)
		(property "Value" "+5V"
			(at 110.49 119.38 0)
			(effects
				(font
					(size 1.27 1.27)
					(thickness 0.15)
				)
				(justify left)
			)
		)
		(property "Footprint" ""
			(at 128.27 130.81 0)
			(effects
				(font
					(size 1.27 1.27)
					(thickness 0.15)
				)
				(justify left bottom)
				(hide yes)
			)
		)
		(property "Datasheet" ""
			(at 128.27 133.35 0)
			(effects
				(font
					(size 1.27 1.27)
					(thickness 0.15)
				)
				(justify left bottom)
				(hide yes)
			)
		)
		(property "Description" ""
			(at 113.03 123.19 0)
			(effects
				(font
					(size 1.27 1.27)
				)
				(hide yes)
			)
		)
		(property "Author" "Antmicro"
			(at 128.27 130.81 0)
			(effects
				(font
					(size 1.27 1.27)
					(thickness 0.15)
				)
				(justify left bottom)
				(hide yes)
			)
		)
		(property "License" "Apache-2.0"
			(at 128.27 133.35 0)
			(effects
				(font
					(size 1.27 1.27)
					(thickness 0.15)
				)
				(justify left bottom)
				(hide yes)
			)
		)
		(pin "1"
		)
		(instances
			(project "jetson-orin-baseboard"
				(path ""
					(reference "#PWR0110")
					(unit 1)
				)
			)
		)
	)
	(symbol
		(lib_name "GND_3")
		(lib_id "antmicropower:GND")
		(at 267.97 95.25 0)
		(unit 1)
		(exclude_from_sim no)
		(in_bom yes)
		(on_board yes)
		(dnp no)
		(fields_autoplaced yes)
		(property "Reference" "#PWR0128"
			(at 267.97 101.6 0)
			(effects
				(font
					(size 1.27 1.27)
				)
				(justify left bottom)
				(hide yes)
			)
		)
		(property "Value" "GND"
			(at 267.97 99.06 0)
			(effects
				(font
					(size 1.27 1.27)
					(thickness 0.15)
				)
			)
		)
		(property "Footprint" ""
			(at 276.86 102.87 0)
			(effects
				(font
					(size 1.27 1.27)
					(thickness 0.15)
				)
				(justify left bottom)
				(hide yes)
			)
		)
		(property "Datasheet" ""
			(at 276.86 107.95 0)
			(effects
				(font
					(size 1.27 1.27)
					(thickness 0.15)
				)
				(justify left bottom)
				(hide yes)
			)
		)
		(property "Description" ""
			(at 267.97 95.25 0)
			(effects
				(font
					(size 1.27 1.27)
				)
				(hide yes)
			)
		)
		(property "Author" "Antmicro"
			(at 276.86 102.87 0)
			(effects
				(font
					(size 1.27 1.27)
					(thickness 0.15)
				)
				(justify left bottom)
				(hide yes)
			)
		)
		(property "License" "Apache-2.0"
			(at 276.86 105.41 0)
			(effects
				(font
					(size 1.27 1.27)
					(thickness 0.15)
				)
				(justify left bottom)
				(hide yes)
			)
		)
		(pin "1"
		)
		(instances
			(project "jetson-orin-baseboard"
				(path ""
					(reference "#PWR0128")
					(unit 1)
				)
			)
		)
	)
	(symbol
		(lib_name "R_0R_0402_1")
		(lib_id "antmicroResistors0402:R_0R_0402")
		(at 81.28 187.96 90)
		(unit 1)
		(exclude_from_sim no)
		(in_bom no)
		(on_board yes)
		(dnp yes)
		(property "Reference" "R114"
			(at 82.55 184.15 90)
			(effects
				(font
					(size 1.27 1.27)
				)
				(justify right)
			)
		)
		(property "Value" "R_0R_0402"
			(at 93.98 167.64 0)
			(effects
				(font
					(size 1.27 1.27)
					(thickness 0.15)
				)
				(justify left bottom)
				(hide yes)
			)
		)
		(property "Footprint" "antmicro-footprints:R_0402_1005Metric"
			(at 96.52 167.64 0)
			(effects
				(font
					(size 1.27 1.27)
					(thickness 0.15)
				)
				(justify left bottom)
				(hide yes)
			)
		)
		(property "Datasheet" "https://industrial.panasonic.com/cdbs/www-data/pdf/RDA0000/AOA0000C301.pdf"
			(at 99.06 167.64 0)
			(effects
				(font
					(size 1.27 1.27)
					(thickness 0.15)
				)
				(justify left bottom)
				(hide yes)
			)
		)
		(property "Description" ""
			(at 81.28 187.96 0)
			(effects
				(font
					(size 1.27 1.27)
				)
				(hide yes)
			)
		)
		(property "Manufacturer" "Panasonic"
			(at 104.14 167.64 0)
			(effects
				(font
					(size 1.27 1.27)
					(thickness 0.15)
				)
				(justify left bottom)
				(hide yes)
			)
		)
		(property "MPN" "ERJ2GE0R00X"
			(at 101.6 167.64 0)
			(effects
				(font
					(size 1.27 1.27)
					(thickness 0.15)
				)
				(justify left bottom)
				(hide yes)
			)
		)
		(property "Val" "0R"
			(at 82.55 186.69 90)
			(effects
				(font
					(size 1.27 1.27)
					(thickness 0.15)
				)
				(justify right)
			)
		)
		(property "License" "Apache-2.0"
			(at 106.68 167.64 0)
			(effects
				(font
					(size 1.27 1.27)
					(thickness 0.15)
				)
				(justify left bottom)
				(hide yes)
			)
		)
		(property "Author" "Antmicro"
			(at 109.22 167.64 0)
			(effects
				(font
					(size 1.27 1.27)
					(thickness 0.15)
				)
				(justify left bottom)
				(hide yes)
			)
		)
		(property "Tolerance" "~"
			(at 91.44 167.64 0)
			(effects
				(font
					(size 1.27 1.27)
				)
				(justify left bottom)
				(hide yes)
			)
		)
		(property "Current" "1A"
			(at 111.76 167.64 0)
			(effects
				(font
					(size 1.27 1.27)
					(thickness 0.15)
				)
				(justify left bottom)
				(hide yes)
			)
		)
		(pin "1"
		)
		(pin "2"
		)
		(instances
			(project "jetson-orin-baseboard"
				(path ""
					(reference "R114")
					(unit 1)
				)
			)
		)
	)
	(symbol
		(lib_id "antmicropower:+5V")
		(at 199.39 107.95 0)
		(mirror y)
		(unit 1)
		(exclude_from_sim no)
		(in_bom yes)
		(on_board yes)
		(dnp no)
		(property "Reference" "#PWR0120"
			(at 199.39 111.76 0)
			(effects
				(font
					(size 1.27 1.27)
				)
				(justify left bottom)
				(hide yes)
			)
		)
		(property "Value" "+5V"
			(at 196.85 104.14 0)
			(effects
				(font
					(size 1.27 1.27)
					(thickness 0.15)
				)
				(justify right)
			)
		)
		(property "Footprint" ""
			(at 184.15 115.57 0)
			(effects
				(font
					(size 1.27 1.27)
					(thickness 0.15)
				)
				(justify left bottom)
				(hide yes)
			)
		)
		(property "Datasheet" ""
			(at 184.15 118.11 0)
			(effects
				(font
					(size 1.27 1.27)
					(thickness 0.15)
				)
				(justify left bottom)
				(hide yes)
			)
		)
		(property "Description" ""
			(at 199.39 107.95 0)
			(effects
				(font
					(size 1.27 1.27)
				)
				(hide yes)
			)
		)
		(property "Author" "Antmicro"
			(at 184.15 115.57 0)
			(effects
				(font
					(size 1.27 1.27)
					(thickness 0.15)
				)
				(justify left bottom)
				(hide yes)
			)
		)
		(property "License" "Apache-2.0"
			(at 184.15 118.11 0)
			(effects
				(font
					(size 1.27 1.27)
					(thickness 0.15)
				)
				(justify left bottom)
				(hide yes)
			)
		)
		(pin "1"
		)
		(instances
			(project "jetson-orin-baseboard"
				(path ""
					(reference "#PWR0120")
					(unit 1)
				)
			)
		)
	)
	(symbol
		(lib_name "R_200k_0402_1")
		(lib_id "antmicroResistors0402:R_200k_0402")
		(at 132.08 191.77 180)
		(unit 1)
		(exclude_from_sim no)
		(in_bom yes)
		(on_board yes)
		(dnp no)
		(property "Reference" "R265"
			(at 137.16 189.865 0)
			(effects
				(font
					(size 1.27 1.27)
				)
				(justify left bottom)
			)
		)
		(property "Value" "R_200k_0402"
			(at 111.76 179.07 0)
			(effects
				(font
					(size 1.27 1.27)
					(thickness 0.15)
				)
				(justify left bottom)
				(hide yes)
			)
		)
		(property "Footprint" "antmicro-footprints:R_0402_1005Metric"
			(at 111.76 176.53 0)
			(effects
				(font
					(size 1.27 1.27)
					(thickness 0.15)
				)
				(justify left bottom)
				(hide yes)
			)
		)
		(property "Datasheet" "https://www.bourns.com/docs/product-datasheets/cr.pdf"
			(at 111.76 173.99 0)
			(effects
				(font
					(size 1.27 1.27)
					(thickness 0.15)
				)
				(justify left bottom)
				(hide yes)
			)
		)
		(property "Description" ""
			(at 132.08 191.77 0)
			(effects
				(font
					(size 1.27 1.27)
				)
				(hide yes)
			)
		)
		(property "Manufacturer" "Bourns"
			(at 111.76 168.91 0)
			(effects
				(font
					(size 1.27 1.27)
					(thickness 0.15)
				)
				(justify left bottom)
				(hide yes)
			)
		)
		(property "MPN" "CR0402-FX-2003GLF"
			(at 111.76 171.45 0)
			(effects
				(font
					(size 1.27 1.27)
					(thickness 0.15)
				)
				(justify left bottom)
				(hide yes)
			)
		)
		(property "Val" "200k"
			(at 127 189.865 0)
			(effects
				(font
					(size 1.27 1.27)
					(thickness 0.15)
				)
				(justify left bottom)
			)
		)
		(property "License" "Apache-2.0"
			(at 111.76 166.37 0)
			(effects
				(font
					(size 1.27 1.27)
					(thickness 0.15)
				)
				(justify left bottom)
				(hide yes)
			)
		)
		(property "Author" "Antmicro"
			(at 111.76 163.83 0)
			(effects
				(font
					(size 1.27 1.27)
					(thickness 0.15)
				)
				(justify left bottom)
				(hide yes)
			)
		)
		(property "Tolerance" "1%"
			(at 111.76 181.61 0)
			(effects
				(font
					(size 1.27 1.27)
				)
				(justify left bottom)
				(hide yes)
			)
		)
		(pin "1"
		)
		(pin "2"
		)
		(instances
			(project "jetson-orin-baseboard"
				(path ""
					(reference "R265")
					(unit 1)
				)
			)
		)
	)
	(symbol
		(lib_id "antmicroCapacitors0603:C_10u_0603")
		(at 267.97 88.9 90)
		(mirror x)
		(unit 1)
		(exclude_from_sim no)
		(in_bom yes)
		(on_board yes)
		(dnp no)
		(fields_autoplaced yes)
		(property "Reference" "C74"
			(at 270.51 90.1763 90)
			(effects
				(font
					(size 1.27 1.27)
				)
				(justify right)
			)
		)
		(property "Value" "C_10u_0603"
			(at 278.13 109.22 0)
			(effects
				(font
					(size 1.27 1.27)
					(thickness 0.15)
				)
				(justify left bottom)
				(hide yes)
			)
		)
		(property "Footprint" "antmicro-footprints:C_0603_1608Metric"
			(at 280.67 109.22 0)
			(effects
				(font
					(size 1.27 1.27)
					(thickness 0.15)
				)
				(justify left bottom)
				(hide yes)
			)
		)
		(property "Datasheet" "https://www.murata.com/products/productdetail?partno=GRM188R61A106KE69%23"
			(at 283.21 109.22 0)
			(effects
				(font
					(size 1.27 1.27)
					(thickness 0.15)
				)
				(justify left bottom)
				(hide yes)
			)
		)
		(property "Description" ""
			(at 267.97 88.9 0)
			(effects
				(font
					(size 1.27 1.27)
				)
				(hide yes)
			)
		)
		(property "Manufacturer" "Murata"
			(at 288.29 109.22 0)
			(effects
				(font
					(size 1.27 1.27)
					(thickness 0.15)
				)
				(justify left bottom)
				(hide yes)
			)
		)
		(property "MPN" "GRM188R61A106KE69D"
			(at 285.75 109.22 0)
			(effects
				(font
					(size 1.27 1.27)
					(thickness 0.15)
				)
				(justify left bottom)
				(hide yes)
			)
		)
		(property "Val" "10u"
			(at 270.51 92.7163 90)
			(effects
				(font
					(size 1.27 1.27)
					(thickness 0.15)
				)
				(justify right)
			)
		)
		(property "License" "Apache-2.0"
			(at 290.83 109.22 0)
			(effects
				(font
					(size 1.27 1.27)
					(thickness 0.15)
				)
				(justify left bottom)
				(hide yes)
			)
		)
		(property "Author" "Antmicro"
			(at 293.37 109.22 0)
			(effects
				(font
					(size 1.27 1.27)
					(thickness 0.15)
				)
				(justify left bottom)
				(hide yes)
			)
		)
		(property "Voltage" ""
			(at 295.91 109.22 0)
			(effects
				(font
					(size 1.27 1.27)
				)
				(justify left bottom)
				(hide yes)
			)
		)
		(property "Dielectric" "template_dielectric"
			(at 298.45 109.22 0)
			(effects
				(font
					(size 1.27 1.27)
				)
				(justify left bottom)
				(hide yes)
			)
		)
		(pin "1"
		)
		(pin "2"
		)
		(instances
			(project "jetson-orin-baseboard"
				(path ""
					(reference "C74")
					(unit 1)
				)
			)
		)
	)
	(symbol
		(lib_name "R_0R_0402_2")
		(lib_id "antmicroResistors0402:R_0R_0402")
		(at 119.38 165.1 0)
		(unit 1)
		(exclude_from_sim no)
		(in_bom yes)
		(on_board yes)
		(dnp no)
		(property "Reference" "R203"
			(at 124.46 164.465 0)
			(effects
				(font
					(size 1.27 1.27)
				)
				(justify left bottom)
			)
		)
		(property "Value" "R_0R_0402"
			(at 139.7 177.8 0)
			(effects
				(font
					(size 1.27 1.27)
					(thickness 0.15)
				)
				(justify left bottom)
				(hide yes)
			)
		)
		(property "Footprint" "antmicro-footprints:R_0402_1005Metric"
			(at 139.7 180.34 0)
			(effects
				(font
					(size 1.27 1.27)
					(thickness 0.15)
				)
				(justify left bottom)
				(hide yes)
			)
		)
		(property "Datasheet" "https://industrial.panasonic.com/cdbs/www-data/pdf/RDA0000/AOA0000C301.pdf"
			(at 139.7 182.88 0)
			(effects
				(font
					(size 1.27 1.27)
					(thickness 0.15)
				)
				(justify left bottom)
				(hide yes)
			)
		)
		(property "Description" ""
			(at 119.38 165.1 0)
			(effects
				(font
					(size 1.27 1.27)
				)
				(hide yes)
			)
		)
		(property "Manufacturer" "Panasonic"
			(at 139.7 187.96 0)
			(effects
				(font
					(size 1.27 1.27)
					(thickness 0.15)
				)
				(justify left bottom)
				(hide yes)
			)
		)
		(property "MPN" "ERJ2GE0R00X"
			(at 139.7 185.42 0)
			(effects
				(font
					(size 1.27 1.27)
					(thickness 0.15)
				)
				(justify left bottom)
				(hide yes)
			)
		)
		(property "Val" "0R"
			(at 116.84 164.465 0)
			(effects
				(font
					(size 1.27 1.27)
					(thickness 0.15)
				)
				(justify left bottom)
			)
		)
		(property "License" "Apache-2.0"
			(at 139.7 190.5 0)
			(effects
				(font
					(size 1.27 1.27)
					(thickness 0.15)
				)
				(justify left bottom)
				(hide yes)
			)
		)
		(property "Author" "Antmicro"
			(at 139.7 193.04 0)
			(effects
				(font
					(size 1.27 1.27)
					(thickness 0.15)
				)
				(justify left bottom)
				(hide yes)
			)
		)
		(property "Tolerance" "~"
			(at 139.7 175.26 0)
			(effects
				(font
					(size 1.27 1.27)
				)
				(justify left bottom)
				(hide yes)
			)
		)
		(property "Current" "1A"
			(at 139.7 195.58 0)
			(effects
				(font
					(size 1.27 1.27)
					(thickness 0.15)
				)
				(justify left bottom)
				(hide yes)
			)
		)
		(pin "1"
		)
		(pin "2"
		)
		(instances
			(project "jetson-orin-baseboard"
				(path ""
					(reference "R203")
					(unit 1)
				)
			)
		)
	)
	(symbol
		(lib_name "GND_3")
		(lib_id "antmicropower:GND")
		(at 81.28 189.23 0)
		(unit 1)
		(exclude_from_sim no)
		(in_bom yes)
		(on_board yes)
		(dnp no)
		(property "Reference" "#PWR0109"
			(at 81.28 195.58 0)
			(effects
				(font
					(size 1.27 1.27)
				)
				(justify left bottom)
				(hide yes)
			)
		)
		(property "Value" "GND"
			(at 81.28 193.04 0)
			(effects
				(font
					(size 1.27 1.27)
					(thickness 0.15)
				)
			)
		)
		(property "Footprint" ""
			(at 90.17 196.85 0)
			(effects
				(font
					(size 1.27 1.27)
					(thickness 0.15)
				)
				(justify left bottom)
				(hide yes)
			)
		)
		(property "Datasheet" ""
			(at 90.17 201.93 0)
			(effects
				(font
					(size 1.27 1.27)
					(thickness 0.15)
				)
				(justify left bottom)
				(hide yes)
			)
		)
		(property "Description" ""
			(at 81.28 189.23 0)
			(effects
				(font
					(size 1.27 1.27)
				)
				(hide yes)
			)
		)
		(property "Author" "Antmicro"
			(at 90.17 196.85 0)
			(effects
				(font
					(size 1.27 1.27)
					(thickness 0.15)
				)
				(justify left bottom)
				(hide yes)
			)
		)
		(property "License" "Apache-2.0"
			(at 90.17 199.39 0)
			(effects
				(font
					(size 1.27 1.27)
					(thickness 0.15)
				)
				(justify left bottom)
				(hide yes)
			)
		)
		(pin "1"
		)
		(instances
			(project "jetson-orin-baseboard"
				(path ""
					(reference "#PWR0109")
					(unit 1)
				)
			)
		)
	)
	(symbol
		(lib_name "C_100n_0402_1")
		(lib_id "antmicroCapacitors0402:C_100n_0402")
		(at 151.13 102.87 90)
		(mirror x)
		(unit 1)
		(exclude_from_sim no)
		(in_bom yes)
		(on_board yes)
		(dnp no)
		(fields_autoplaced yes)
		(property "Reference" "C67"
			(at 153.67 104.1463 90)
			(effects
				(font
					(size 1.27 1.27)
				)
				(justify right)
			)
		)
		(property "Value" "C_100n_0402"
			(at 161.29 123.19 0)
			(effects
				(font
					(size 1.27 1.27)
					(thickness 0.15)
				)
				(justify left bottom)
				(hide yes)
			)
		)
		(property "Footprint" "antmicro-footprints:C_0402_1005Metric"
			(at 163.83 123.19 0)
			(effects
				(font
					(size 1.27 1.27)
					(thickness 0.15)
				)
				(justify left bottom)
				(hide yes)
			)
		)
		(property "Datasheet" "https://www.murata.com/products/productdetail?partno=GRM155R61H104KE14%23"
			(at 166.37 123.19 0)
			(effects
				(font
					(size 1.27 1.27)
					(thickness 0.15)
				)
				(justify left bottom)
				(hide yes)
			)
		)
		(property "Description" ""
			(at 151.13 102.87 0)
			(effects
				(font
					(size 1.27 1.27)
				)
				(hide yes)
			)
		)
		(property "Manufacturer" "Murata"
			(at 171.45 123.19 0)
			(effects
				(font
					(size 1.27 1.27)
					(thickness 0.15)
				)
				(justify left bottom)
				(hide yes)
			)
		)
		(property "MPN" "GRM155R61H104KE14D"
			(at 168.91 123.19 0)
			(effects
				(font
					(size 1.27 1.27)
					(thickness 0.15)
				)
				(justify left bottom)
				(hide yes)
			)
		)
		(property "Val" "100n"
			(at 153.67 106.6863 90)
			(effects
				(font
					(size 1.27 1.27)
					(thickness 0.15)
				)
				(justify right)
			)
		)
		(property "License" "Apache-2.0"
			(at 173.99 123.19 0)
			(effects
				(font
					(size 1.27 1.27)
					(thickness 0.15)
				)
				(justify left bottom)
				(hide yes)
			)
		)
		(property "Author" "Antmicro"
			(at 176.53 123.19 0)
			(effects
				(font
					(size 1.27 1.27)
					(thickness 0.15)
				)
				(justify left bottom)
				(hide yes)
			)
		)
		(property "Voltage" "50V"
			(at 179.07 123.19 0)
			(effects
				(font
					(size 1.27 1.27)
				)
				(justify left bottom)
				(hide yes)
			)
		)
		(property "Dielectric" "X5R"
			(at 181.61 123.19 0)
			(effects
				(font
					(size 1.27 1.27)
				)
				(justify left bottom)
				(hide yes)
			)
		)
		(pin "1"
		)
		(pin "2"
		)
		(instances
			(project "jetson-orin-baseboard"
				(path ""
					(reference "C67")
					(unit 1)
				)
			)
		)
	)
	(symbol
		(lib_name "R_10k_0402_1")
		(lib_id "antmicroResistors0402:R_10k_0402")
		(at 121.92 132.08 90)
		(unit 1)
		(exclude_from_sim no)
		(in_bom yes)
		(on_board yes)
		(dnp no)
		(property "Reference" "R116"
			(at 123.19 128.27 90)
			(effects
				(font
					(size 1.27 1.27)
				)
				(justify right)
			)
		)
		(property "Value" "R_10k_0402"
			(at 134.62 111.76 0)
			(effects
				(font
					(size 1.27 1.27)
					(thickness 0.15)
				)
				(justify left bottom)
				(hide yes)
			)
		)
		(property "Footprint" "antmicro-footprints:R_0402_1005Metric"
			(at 137.16 111.76 0)
			(effects
				(font
					(size 1.27 1.27)
					(thickness 0.15)
				)
				(justify left bottom)
				(hide yes)
			)
		)
		(property "Datasheet" "https://www.bourns.com/docs/product-datasheets/cr.pdf"
			(at 139.7 111.76 0)
			(effects
				(font
					(size 1.27 1.27)
					(thickness 0.15)
				)
				(justify left bottom)
				(hide yes)
			)
		)
		(property "Description" ""
			(at 121.92 132.08 0)
			(effects
				(font
					(size 1.27 1.27)
				)
				(hide yes)
			)
		)
		(property "Manufacturer" "Bourns"
			(at 144.78 111.76 0)
			(effects
				(font
					(size 1.27 1.27)
					(thickness 0.15)
				)
				(justify left bottom)
				(hide yes)
			)
		)
		(property "MPN" "CR0402-FX-1002GLF"
			(at 142.24 111.76 0)
			(effects
				(font
					(size 1.27 1.27)
					(thickness 0.15)
				)
				(justify left bottom)
				(hide yes)
			)
		)
		(property "Val" "10k"
			(at 123.19 130.81 90)
			(effects
				(font
					(size 1.27 1.27)
					(thickness 0.15)
				)
				(justify right)
			)
		)
		(property "License" "Apache-2.0"
			(at 147.32 111.76 0)
			(effects
				(font
					(size 1.27 1.27)
					(thickness 0.15)
				)
				(justify left bottom)
				(hide yes)
			)
		)
		(property "Author" "Antmicro"
			(at 149.86 111.76 0)
			(effects
				(font
					(size 1.27 1.27)
					(thickness 0.15)
				)
				(justify left bottom)
				(hide yes)
			)
		)
		(property "Tolerance" "1%"
			(at 132.08 111.76 0)
			(effects
				(font
					(size 1.27 1.27)
				)
				(justify left bottom)
				(hide yes)
			)
		)
		(pin "1"
		)
		(pin "2"
		)
		(instances
			(project "jetson-orin-baseboard"
				(path ""
					(reference "R116")
					(unit 1)
				)
			)
		)
	)
	(symbol
		(lib_id "antmicroResistors0402:R_200k_0402")
		(at 345.44 86.36 90)
		(unit 1)
		(exclude_from_sim no)
		(in_bom yes)
		(on_board yes)
		(dnp no)
		(property "Reference" "R61"
			(at 346.71 82.55 90)
			(effects
				(font
					(size 1.27 1.27)
				)
				(justify right)
			)
		)
		(property "Value" "R_200k_0402"
			(at 358.14 66.04 0)
			(effects
				(font
					(size 1.27 1.27)
					(thickness 0.15)
				)
				(justify left bottom)
				(hide yes)
			)
		)
		(property "Footprint" "antmicro-footprints:R_0402_1005Metric"
			(at 360.68 66.04 0)
			(effects
				(font
					(size 1.27 1.27)
					(thickness 0.15)
				)
				(justify left bottom)
				(hide yes)
			)
		)
		(property "Datasheet" "https://www.bourns.com/docs/product-datasheets/cr.pdf"
			(at 363.22 66.04 0)
			(effects
				(font
					(size 1.27 1.27)
					(thickness 0.15)
				)
				(justify left bottom)
				(hide yes)
			)
		)
		(property "Description" ""
			(at 345.44 86.36 0)
			(effects
				(font
					(size 1.27 1.27)
				)
				(hide yes)
			)
		)
		(property "Manufacturer" "Bourns"
			(at 368.3 66.04 0)
			(effects
				(font
					(size 1.27 1.27)
					(thickness 0.15)
				)
				(justify left bottom)
				(hide yes)
			)
		)
		(property "MPN" "CR0402-FX-2003GLF"
			(at 365.76 66.04 0)
			(effects
				(font
					(size 1.27 1.27)
					(thickness 0.15)
				)
				(justify left bottom)
				(hide yes)
			)
		)
		(property "Val" "200k"
			(at 346.71 85.09 90)
			(effects
				(font
					(size 1.27 1.27)
					(thickness 0.15)
				)
				(justify right)
			)
		)
		(property "License" "Apache-2.0"
			(at 370.84 66.04 0)
			(effects
				(font
					(size 1.27 1.27)
					(thickness 0.15)
				)
				(justify left bottom)
				(hide yes)
			)
		)
		(property "Author" "Antmicro"
			(at 373.38 66.04 0)
			(effects
				(font
					(size 1.27 1.27)
					(thickness 0.15)
				)
				(justify left bottom)
				(hide yes)
			)
		)
		(property "Tolerance" "1%"
			(at 355.6 66.04 0)
			(effects
				(font
					(size 1.27 1.27)
				)
				(justify left bottom)
				(hide yes)
			)
		)
		(pin "1"
		)
		(pin "2"
		)
		(instances
			(project "jetson-orin-baseboard"
				(path ""
					(reference "R61")
					(unit 1)
				)
			)
		)
	)
	(symbol
		(lib_name "GND_3")
		(lib_id "antmicropower:GND")
		(at 309.88 101.6 0)
		(unit 1)
		(exclude_from_sim no)
		(in_bom yes)
		(on_board yes)
		(dnp no)
		(property "Reference" "#PWR0132"
			(at 309.88 107.95 0)
			(effects
				(font
					(size 1.27 1.27)
				)
				(justify left bottom)
				(hide yes)
			)
		)
		(property "Value" "GND"
			(at 309.88 105.41 0)
			(effects
				(font
					(size 1.27 1.27)
					(thickness 0.15)
				)
			)
		)
		(property "Footprint" ""
			(at 318.77 109.22 0)
			(effects
				(font
					(size 1.27 1.27)
					(thickness 0.15)
				)
				(justify left bottom)
				(hide yes)
			)
		)
		(property "Datasheet" ""
			(at 318.77 114.3 0)
			(effects
				(font
					(size 1.27 1.27)
					(thickness 0.15)
				)
				(justify left bottom)
				(hide yes)
			)
		)
		(property "Description" ""
			(at 309.88 101.6 0)
			(effects
				(font
					(size 1.27 1.27)
				)
				(hide yes)
			)
		)
		(property "Author" "Antmicro"
			(at 318.77 109.22 0)
			(effects
				(font
					(size 1.27 1.27)
					(thickness 0.15)
				)
				(justify left bottom)
				(hide yes)
			)
		)
		(property "License" "Apache-2.0"
			(at 318.77 111.76 0)
			(effects
				(font
					(size 1.27 1.27)
					(thickness 0.15)
				)
				(justify left bottom)
				(hide yes)
			)
		)
		(pin "1"
		)
		(instances
			(project "jetson-orin-baseboard"
				(path ""
					(reference "#PWR0132")
					(unit 1)
				)
			)
		)
	)
	(symbol
		(lib_id "antmicroCapacitors0402:C_100n_0402")
		(at 278.13 88.9 90)
		(mirror x)
		(unit 1)
		(exclude_from_sim no)
		(in_bom yes)
		(on_board yes)
		(dnp no)
		(fields_autoplaced yes)
		(property "Reference" "C75"
			(at 280.67 90.1763 90)
			(effects
				(font
					(size 1.27 1.27)
				)
				(justify right)
			)
		)
		(property "Value" "C_100n_0402"
			(at 288.29 109.22 0)
			(effects
				(font
					(size 1.27 1.27)
					(thickness 0.15)
				)
				(justify left bottom)
				(hide yes)
			)
		)
		(property "Footprint" "antmicro-footprints:C_0402_1005Metric"
			(at 290.83 109.22 0)
			(effects
				(font
					(size 1.27 1.27)
					(thickness 0.15)
				)
				(justify left bottom)
				(hide yes)
			)
		)
		(property "Datasheet" "https://www.murata.com/products/productdetail?partno=GRM155R61H104KE14%23"
			(at 293.37 109.22 0)
			(effects
				(font
					(size 1.27 1.27)
					(thickness 0.15)
				)
				(justify left bottom)
				(hide yes)
			)
		)
		(property "Description" ""
			(at 278.13 88.9 0)
			(effects
				(font
					(size 1.27 1.27)
				)
				(hide yes)
			)
		)
		(property "Manufacturer" "Murata"
			(at 298.45 109.22 0)
			(effects
				(font
					(size 1.27 1.27)
					(thickness 0.15)
				)
				(justify left bottom)
				(hide yes)
			)
		)
		(property "MPN" "GRM155R61H104KE14D"
			(at 295.91 109.22 0)
			(effects
				(font
					(size 1.27 1.27)
					(thickness 0.15)
				)
				(justify left bottom)
				(hide yes)
			)
		)
		(property "Val" "100n"
			(at 280.67 92.7163 90)
			(effects
				(font
					(size 1.27 1.27)
					(thickness 0.15)
				)
				(justify right)
			)
		)
		(property "License" "Apache-2.0"
			(at 300.99 109.22 0)
			(effects
				(font
					(size 1.27 1.27)
					(thickness 0.15)
				)
				(justify left bottom)
				(hide yes)
			)
		)
		(property "Author" "Antmicro"
			(at 303.53 109.22 0)
			(effects
				(font
					(size 1.27 1.27)
					(thickness 0.15)
				)
				(justify left bottom)
				(hide yes)
			)
		)
		(property "Voltage" "50V"
			(at 306.07 109.22 0)
			(effects
				(font
					(size 1.27 1.27)
				)
				(justify left bottom)
				(hide yes)
			)
		)
		(property "Dielectric" "X5R"
			(at 308.61 109.22 0)
			(effects
				(font
					(size 1.27 1.27)
				)
				(justify left bottom)
				(hide yes)
			)
		)
		(pin "1"
		)
		(pin "2"
		)
		(instances
			(project "jetson-orin-baseboard"
				(path ""
					(reference "C75")
					(unit 1)
				)
			)
		)
	)
	(symbol
		(lib_name "R_0R_0402_3")
		(lib_id "antmicroResistors0402:R_0R_0402")
		(at 120.65 142.24 0)
		(unit 1)
		(exclude_from_sim no)
		(in_bom yes)
		(on_board yes)
		(dnp no)
		(property "Reference" "R119"
			(at 125.73 141.605 0)
			(effects
				(font
					(size 1.27 1.27)
				)
				(justify left bottom)
			)
		)
		(property "Value" "R_0R_0402"
			(at 140.97 154.94 0)
			(effects
				(font
					(size 1.27 1.27)
					(thickness 0.15)
				)
				(justify left bottom)
				(hide yes)
			)
		)
		(property "Footprint" "antmicro-footprints:R_0402_1005Metric"
			(at 140.97 157.48 0)
			(effects
				(font
					(size 1.27 1.27)
					(thickness 0.15)
				)
				(justify left bottom)
				(hide yes)
			)
		)
		(property "Datasheet" "https://industrial.panasonic.com/cdbs/www-data/pdf/RDA0000/AOA0000C301.pdf"
			(at 140.97 160.02 0)
			(effects
				(font
					(size 1.27 1.27)
					(thickness 0.15)
				)
				(justify left bottom)
				(hide yes)
			)
		)
		(property "Description" ""
			(at 120.65 142.24 0)
			(effects
				(font
					(size 1.27 1.27)
				)
				(hide yes)
			)
		)
		(property "Manufacturer" "Panasonic"
			(at 140.97 165.1 0)
			(effects
				(font
					(size 1.27 1.27)
					(thickness 0.15)
				)
				(justify left bottom)
				(hide yes)
			)
		)
		(property "MPN" "ERJ2GE0R00X"
			(at 140.97 162.56 0)
			(effects
				(font
					(size 1.27 1.27)
					(thickness 0.15)
				)
				(justify left bottom)
				(hide yes)
			)
		)
		(property "Val" "0R"
			(at 118.11 141.605 0)
			(effects
				(font
					(size 1.27 1.27)
					(thickness 0.15)
				)
				(justify left bottom)
			)
		)
		(property "License" "Apache-2.0"
			(at 140.97 167.64 0)
			(effects
				(font
					(size 1.27 1.27)
					(thickness 0.15)
				)
				(justify left bottom)
				(hide yes)
			)
		)
		(property "Author" "Antmicro"
			(at 140.97 170.18 0)
			(effects
				(font
					(size 1.27 1.27)
					(thickness 0.15)
				)
				(justify left bottom)
				(hide yes)
			)
		)
		(property "Tolerance" "~"
			(at 140.97 152.4 0)
			(effects
				(font
					(size 1.27 1.27)
				)
				(justify left bottom)
				(hide yes)
			)
		)
		(property "Current" "1A"
			(at 140.97 172.72 0)
			(effects
				(font
					(size 1.27 1.27)
					(thickness 0.15)
				)
				(justify left bottom)
				(hide yes)
			)
		)
		(pin "1"
		)
		(pin "2"
		)
		(instances
			(project "jetson-orin-baseboard"
				(path ""
					(reference "R119")
					(unit 1)
				)
			)
		)
	)
	(symbol
		(lib_name "GND_3")
		(lib_id "antmicropower:GND")
		(at 290.83 95.25 0)
		(unit 1)
		(exclude_from_sim no)
		(in_bom yes)
		(on_board yes)
		(dnp no)
		(property "Reference" "#PWR0130"
			(at 290.83 101.6 0)
			(effects
				(font
					(size 1.27 1.27)
				)
				(justify left bottom)
				(hide yes)
			)
		)
		(property "Value" "GND"
			(at 290.83 99.06 0)
			(effects
				(font
					(size 1.27 1.27)
					(thickness 0.15)
				)
			)
		)
		(property "Footprint" ""
			(at 299.72 102.87 0)
			(effects
				(font
					(size 1.27 1.27)
					(thickness 0.15)
				)
				(justify left bottom)
				(hide yes)
			)
		)
		(property "Datasheet" ""
			(at 299.72 107.95 0)
			(effects
				(font
					(size 1.27 1.27)
					(thickness 0.15)
				)
				(justify left bottom)
				(hide yes)
			)
		)
		(property "Description" ""
			(at 290.83 95.25 0)
			(effects
				(font
					(size 1.27 1.27)
				)
				(hide yes)
			)
		)
		(property "Author" "Antmicro"
			(at 299.72 102.87 0)
			(effects
				(font
					(size 1.27 1.27)
					(thickness 0.15)
				)
				(justify left bottom)
				(hide yes)
			)
		)
		(property "License" "Apache-2.0"
			(at 299.72 105.41 0)
			(effects
				(font
					(size 1.27 1.27)
					(thickness 0.15)
				)
				(justify left bottom)
				(hide yes)
			)
		)
		(pin "1"
		)
		(instances
			(project "jetson-orin-baseboard"
				(path ""
					(reference "#PWR0130")
					(unit 1)
				)
			)
		)
	)
	(symbol
		(lib_name "+3V3_1")
		(lib_id "antmicropower:+3V3")
		(at 138.43 189.23 0)
		(mirror y)
		(unit 1)
		(exclude_from_sim no)
		(in_bom yes)
		(on_board yes)
		(dnp no)
		(property "Reference" "#PWR0331"
			(at 138.43 193.04 0)
			(effects
				(font
					(size 1.27 1.27)
				)
				(justify left bottom)
				(hide yes)
			)
		)
		(property "Value" "+3V3"
			(at 135.255 185.42 0)
			(effects
				(font
					(size 1.27 1.27)
					(thickness 0.15)
				)
				(justify right)
			)
		)
		(property "Footprint" ""
			(at 123.19 196.85 0)
			(effects
				(font
					(size 1.27 1.27)
					(thickness 0.15)
				)
				(justify left bottom)
				(hide yes)
			)
		)
		(property "Datasheet" ""
			(at 123.19 199.39 0)
			(effects
				(font
					(size 1.27 1.27)
					(thickness 0.15)
				)
				(justify left bottom)
				(hide yes)
			)
		)
		(property "Description" ""
			(at 138.43 189.23 0)
			(effects
				(font
					(size 1.27 1.27)
				)
				(hide yes)
			)
		)
		(property "Author" "Antmicro"
			(at 123.19 191.77 0)
			(effects
				(font
					(size 1.27 1.27)
					(thickness 0.15)
				)
				(justify left bottom)
				(hide yes)
			)
		)
		(property "License" "Apache-2.0"
			(at 123.19 194.31 0)
			(effects
				(font
					(size 1.27 1.27)
					(thickness 0.15)
				)
				(justify left bottom)
				(hide yes)
			)
		)
		(pin "1"
		)
		(instances
			(project "jetson-orin-baseboard"
				(path ""
					(reference "#PWR0331")
					(unit 1)
				)
			)
		)
	)
	(symbol
		(lib_id "antmicroTestPoints:TP_0.75mm_SMD")
		(at 212.09 121.92 0)
		(unit 1)
		(exclude_from_sim no)
		(in_bom no)
		(on_board yes)
		(dnp no)
		(property "Reference" "TP31"
			(at 215.9 121.92 0)
			(effects
				(font
					(size 1.27 1.27)
				)
				(justify left)
			)
		)
		(property "Value" "TP_0.75mm_SMD"
			(at 222.25 125.73 0)
			(effects
				(font
					(size 1.27 1.27)
					(thickness 0.15)
				)
				(justify left bottom)
				(hide yes)
			)
		)
		(property "Footprint" "antmicro-footprints:TP_SMD_0.75mm"
			(at 222.25 128.27 0)
			(effects
				(font
					(size 1.27 1.27)
					(thickness 0.15)
				)
				(justify left bottom)
				(hide yes)
			)
		)
		(property "Datasheet" ""
			(at 229.87 134.62 0)
			(effects
				(font
					(size 1.27 1.27)
					(thickness 0.15)
				)
				(justify left bottom)
				(hide yes)
			)
		)
		(property "Description" ""
			(at 212.09 121.92 0)
			(effects
				(font
					(size 1.27 1.27)
				)
				(hide yes)
			)
		)
		(property "MPN" ""
			(at 222.885 133.35 0)
			(effects
				(font
					(size 1.27 1.27)
					(thickness 0.15)
				)
				(justify left bottom)
				(hide yes)
			)
		)
		(property "Manufacturer" ""
			(at 222.885 128.27 0)
			(effects
				(font
					(size 1.27 1.27)
					(thickness 0.15)
				)
				(justify left bottom)
				(hide yes)
			)
		)
		(property "Author" "Antmicro"
			(at 222.25 130.81 0)
			(effects
				(font
					(size 1.27 1.27)
					(thickness 0.15)
				)
				(justify left bottom)
				(hide yes)
			)
		)
		(property "License" "Apache-2.0"
			(at 222.25 133.35 0)
			(effects
				(font
					(size 1.27 1.27)
					(thickness 0.15)
				)
				(justify left bottom)
				(hide yes)
			)
		)
		(pin "1"
		)
		(instances
			(project "jetson-orin-baseboard"
				(path ""
					(reference "TP31")
					(unit 1)
				)
			)
		)
	)
	(symbol
		(lib_id "antmicroResistors0402:R_10k_0402")
		(at 213.36 83.82 90)
		(unit 1)
		(exclude_from_sim no)
		(in_bom yes)
		(on_board yes)
		(dnp no)
		(property "Reference" "R138"
			(at 214.63 80.01 90)
			(effects
				(font
					(size 1.27 1.27)
				)
				(justify right)
			)
		)
		(property "Value" "R_10k_0402"
			(at 226.06 63.5 0)
			(effects
				(font
					(size 1.27 1.27)
					(thickness 0.15)
				)
				(justify left bottom)
				(hide yes)
			)
		)
		(property "Footprint" "antmicro-footprints:R_0402_1005Metric"
			(at 228.6 63.5 0)
			(effects
				(font
					(size 1.27 1.27)
					(thickness 0.15)
				)
				(justify left bottom)
				(hide yes)
			)
		)
		(property "Datasheet" "https://www.bourns.com/docs/product-datasheets/cr.pdf"
			(at 231.14 63.5 0)
			(effects
				(font
					(size 1.27 1.27)
					(thickness 0.15)
				)
				(justify left bottom)
				(hide yes)
			)
		)
		(property "Description" ""
			(at 213.36 83.82 0)
			(effects
				(font
					(size 1.27 1.27)
				)
				(hide yes)
			)
		)
		(property "Manufacturer" "Bourns"
			(at 236.22 63.5 0)
			(effects
				(font
					(size 1.27 1.27)
					(thickness 0.15)
				)
				(justify left bottom)
				(hide yes)
			)
		)
		(property "MPN" "CR0402-FX-1002GLF"
			(at 233.68 63.5 0)
			(effects
				(font
					(size 1.27 1.27)
					(thickness 0.15)
				)
				(justify left bottom)
				(hide yes)
			)
		)
		(property "Val" "10k"
			(at 214.63 82.55 90)
			(effects
				(font
					(size 1.27 1.27)
					(thickness 0.15)
				)
				(justify right)
			)
		)
		(property "License" "Apache-2.0"
			(at 238.76 63.5 0)
			(effects
				(font
					(size 1.27 1.27)
					(thickness 0.15)
				)
				(justify left bottom)
				(hide yes)
			)
		)
		(property "Author" "Antmicro"
			(at 241.3 63.5 0)
			(effects
				(font
					(size 1.27 1.27)
					(thickness 0.15)
				)
				(justify left bottom)
				(hide yes)
			)
		)
		(property "Tolerance" "1%"
			(at 223.52 63.5 0)
			(effects
				(font
					(size 1.27 1.27)
				)
				(justify left bottom)
				(hide yes)
			)
		)
		(pin "1"
		)
		(pin "2"
		)
		(instances
			(project "jetson-orin-baseboard"
				(path ""
					(reference "R138")
					(unit 1)
				)
			)
		)
	)
	(symbol
		(lib_name "R_0R_0402_4")
		(lib_id "antmicroResistors0402:R_0R_0402")
		(at 119.38 162.56 0)
		(unit 1)
		(exclude_from_sim no)
		(in_bom yes)
		(on_board yes)
		(dnp no)
		(property "Reference" "R202"
			(at 124.46 161.925 0)
			(effects
				(font
					(size 1.27 1.27)
				)
				(justify left bottom)
			)
		)
		(property "Value" "R_0R_0402"
			(at 139.7 175.26 0)
			(effects
				(font
					(size 1.27 1.27)
					(thickness 0.15)
				)
				(justify left bottom)
				(hide yes)
			)
		)
		(property "Footprint" "antmicro-footprints:R_0402_1005Metric"
			(at 139.7 177.8 0)
			(effects
				(font
					(size 1.27 1.27)
					(thickness 0.15)
				)
				(justify left bottom)
				(hide yes)
			)
		)
		(property "Datasheet" "https://industrial.panasonic.com/cdbs/www-data/pdf/RDA0000/AOA0000C301.pdf"
			(at 139.7 180.34 0)
			(effects
				(font
					(size 1.27 1.27)
					(thickness 0.15)
				)
				(justify left bottom)
				(hide yes)
			)
		)
		(property "Description" ""
			(at 119.38 162.56 0)
			(effects
				(font
					(size 1.27 1.27)
				)
				(hide yes)
			)
		)
		(property "Manufacturer" "Panasonic"
			(at 139.7 185.42 0)
			(effects
				(font
					(size 1.27 1.27)
					(thickness 0.15)
				)
				(justify left bottom)
				(hide yes)
			)
		)
		(property "MPN" "ERJ2GE0R00X"
			(at 139.7 182.88 0)
			(effects
				(font
					(size 1.27 1.27)
					(thickness 0.15)
				)
				(justify left bottom)
				(hide yes)
			)
		)
		(property "Val" "0R"
			(at 116.84 161.925 0)
			(effects
				(font
					(size 1.27 1.27)
					(thickness 0.15)
				)
				(justify left bottom)
			)
		)
		(property "License" "Apache-2.0"
			(at 139.7 187.96 0)
			(effects
				(font
					(size 1.27 1.27)
					(thickness 0.15)
				)
				(justify left bottom)
				(hide yes)
			)
		)
		(property "Author" "Antmicro"
			(at 139.7 190.5 0)
			(effects
				(font
					(size 1.27 1.27)
					(thickness 0.15)
				)
				(justify left bottom)
				(hide yes)
			)
		)
		(property "Tolerance" "~"
			(at 139.7 172.72 0)
			(effects
				(font
					(size 1.27 1.27)
				)
				(justify left bottom)
				(hide yes)
			)
		)
		(property "Current" "1A"
			(at 139.7 193.04 0)
			(effects
				(font
					(size 1.27 1.27)
					(thickness 0.15)
				)
				(justify left bottom)
				(hide yes)
			)
		)
		(pin "1"
		)
		(pin "2"
		)
		(instances
			(project "jetson-orin-baseboard"
				(path ""
					(reference "R202")
					(unit 1)
				)
			)
		)
	)
	(symbol
		(lib_name "R_200k_0402_2")
		(lib_id "antmicroResistors0402:R_200k_0402")
		(at 132.08 194.31 180)
		(unit 1)
		(exclude_from_sim no)
		(in_bom yes)
		(on_board yes)
		(dnp no)
		(property "Reference" "R266"
			(at 137.16 192.405 0)
			(effects
				(font
					(size 1.27 1.27)
				)
				(justify left bottom)
			)
		)
		(property "Value" "R_200k_0402"
			(at 111.76 181.61 0)
			(effects
				(font
					(size 1.27 1.27)
					(thickness 0.15)
				)
				(justify left bottom)
				(hide yes)
			)
		)
		(property "Footprint" "antmicro-footprints:R_0402_1005Metric"
			(at 111.76 179.07 0)
			(effects
				(font
					(size 1.27 1.27)
					(thickness 0.15)
				)
				(justify left bottom)
				(hide yes)
			)
		)
		(property "Datasheet" "https://www.bourns.com/docs/product-datasheets/cr.pdf"
			(at 111.76 176.53 0)
			(effects
				(font
					(size 1.27 1.27)
					(thickness 0.15)
				)
				(justify left bottom)
				(hide yes)
			)
		)
		(property "Description" ""
			(at 132.08 194.31 0)
			(effects
				(font
					(size 1.27 1.27)
				)
				(hide yes)
			)
		)
		(property "Manufacturer" "Bourns"
			(at 111.76 171.45 0)
			(effects
				(font
					(size 1.27 1.27)
					(thickness 0.15)
				)
				(justify left bottom)
				(hide yes)
			)
		)
		(property "MPN" "CR0402-FX-2003GLF"
			(at 111.76 173.99 0)
			(effects
				(font
					(size 1.27 1.27)
					(thickness 0.15)
				)
				(justify left bottom)
				(hide yes)
			)
		)
		(property "Val" "200k"
			(at 127 192.405 0)
			(effects
				(font
					(size 1.27 1.27)
					(thickness 0.15)
				)
				(justify left bottom)
			)
		)
		(property "License" "Apache-2.0"
			(at 111.76 168.91 0)
			(effects
				(font
					(size 1.27 1.27)
					(thickness 0.15)
				)
				(justify left bottom)
				(hide yes)
			)
		)
		(property "Author" "Antmicro"
			(at 111.76 166.37 0)
			(effects
				(font
					(size 1.27 1.27)
					(thickness 0.15)
				)
				(justify left bottom)
				(hide yes)
			)
		)
		(property "Tolerance" "1%"
			(at 111.76 184.15 0)
			(effects
				(font
					(size 1.27 1.27)
				)
				(justify left bottom)
				(hide yes)
			)
		)
		(pin "1"
		)
		(pin "2"
		)
		(instances
			(project "jetson-orin-baseboard"
				(path ""
					(reference "R266")
					(unit 1)
				)
			)
		)
	)
	(symbol
		(lib_name "GND_3")
		(lib_id "antmicropower:GND")
		(at 147.32 182.88 0)
		(unit 1)
		(exclude_from_sim no)
		(in_bom yes)
		(on_board yes)
		(dnp no)
		(property "Reference" "#PWR0116"
			(at 147.32 189.23 0)
			(effects
				(font
					(size 1.27 1.27)
				)
				(justify left bottom)
				(hide yes)
			)
		)
		(property "Value" "GND"
			(at 147.32 186.69 0)
			(effects
				(font
					(size 1.27 1.27)
					(thickness 0.15)
				)
			)
		)
		(property "Footprint" ""
			(at 156.21 190.5 0)
			(effects
				(font
					(size 1.27 1.27)
					(thickness 0.15)
				)
				(justify left bottom)
				(hide yes)
			)
		)
		(property "Datasheet" ""
			(at 156.21 195.58 0)
			(effects
				(font
					(size 1.27 1.27)
					(thickness 0.15)
				)
				(justify left bottom)
				(hide yes)
			)
		)
		(property "Description" ""
			(at 147.32 182.88 0)
			(effects
				(font
					(size 1.27 1.27)
				)
				(hide yes)
			)
		)
		(property "Author" "Antmicro"
			(at 156.21 190.5 0)
			(effects
				(font
					(size 1.27 1.27)
					(thickness 0.15)
				)
				(justify left bottom)
				(hide yes)
			)
		)
		(property "License" "Apache-2.0"
			(at 156.21 193.04 0)
			(effects
				(font
					(size 1.27 1.27)
					(thickness 0.15)
				)
				(justify left bottom)
				(hide yes)
			)
		)
		(pin "1"
		)
		(instances
			(project "jetson-orin-baseboard"
				(path ""
					(reference "#PWR0116")
					(unit 1)
				)
			)
		)
	)
	(symbol
		(lib_id "antmicroTransistorsFETsMOSFETsSingle:PJE138K")
		(at 349.25 78.74 0)
		(unit 1)
		(exclude_from_sim no)
		(in_bom yes)
		(on_board yes)
		(dnp no)
		(property "Reference" "Q19"
			(at 358.14 74.93 0)
			(effects
				(font
					(size 1.27 1.27)
					(thickness 0.15)
				)
				(justify left)
			)
		)
		(property "Value" "PJE138K"
			(at 372.11 87.63 0)
			(effects
				(font
					(size 1.27 1.27)
					(thickness 0.15)
				)
				(justify left bottom)
				(hide yes)
			)
		)
		(property "Footprint" "antmicro-footprints:SOT-523"
			(at 372.11 90.17 0)
			(effects
				(font
					(size 1.27 1.27)
					(thickness 0.15)
				)
				(justify left bottom)
				(hide yes)
			)
		)
		(property "Datasheet" "https://www.mouser.com/datasheet/2/1057/PJE138K-1876698.pdf"
			(at 372.11 92.71 0)
			(effects
				(font
					(size 1.27 1.27)
					(thickness 0.15)
				)
				(justify left bottom)
				(hide yes)
			)
		)
		(property "Description" ""
			(at 349.25 78.74 0)
			(effects
				(font
					(size 1.27 1.27)
				)
				(hide yes)
			)
		)
		(property "MPN" "PJE138K_R1_00001"
			(at 358.14 77.47 0)
			(effects
				(font
					(size 1.27 1.27)
					(thickness 0.15)
				)
				(justify left)
			)
		)
		(property "Manufacturer" "PANJIT"
			(at 372.11 97.79 0)
			(effects
				(font
					(size 1.27 1.27)
					(thickness 0.15)
				)
				(justify left bottom)
				(hide yes)
			)
		)
		(property "Author" "Antmicro"
			(at 372.11 100.33 0)
			(effects
				(font
					(size 1.27 1.27)
					(thickness 0.15)
				)
				(justify left bottom)
				(hide yes)
			)
		)
		(property "License" "Apache-2.0"
			(at 372.11 102.87 0)
			(effects
				(font
					(size 1.27 1.27)
					(thickness 0.15)
				)
				(justify left bottom)
				(hide yes)
			)
		)
		(pin "2"
		)
		(pin "3"
		)
		(pin "1"
		)
		(instances
			(project "jetson-orin-baseboard"
				(path ""
					(reference "Q19")
					(unit 1)
				)
			)
		)
	)
	(symbol
		(lib_name "GND_3")
		(lib_id "antmicropower:GND")
		(at 233.68 186.69 0)
		(unit 1)
		(exclude_from_sim no)
		(in_bom yes)
		(on_board yes)
		(dnp no)
		(property "Reference" "#PWR0124"
			(at 233.68 193.04 0)
			(effects
				(font
					(size 1.27 1.27)
				)
				(justify left bottom)
				(hide yes)
			)
		)
		(property "Value" "GND"
			(at 233.68 190.5 0)
			(effects
				(font
					(size 1.27 1.27)
					(thickness 0.15)
				)
			)
		)
		(property "Footprint" ""
			(at 242.57 194.31 0)
			(effects
				(font
					(size 1.27 1.27)
					(thickness 0.15)
				)
				(justify left bottom)
				(hide yes)
			)
		)
		(property "Datasheet" ""
			(at 242.57 199.39 0)
			(effects
				(font
					(size 1.27 1.27)
					(thickness 0.15)
				)
				(justify left bottom)
				(hide yes)
			)
		)
		(property "Description" ""
			(at 233.68 186.69 0)
			(effects
				(font
					(size 1.27 1.27)
				)
				(hide yes)
			)
		)
		(property "Author" "Antmicro"
			(at 242.57 194.31 0)
			(effects
				(font
					(size 1.27 1.27)
					(thickness 0.15)
				)
				(justify left bottom)
				(hide yes)
			)
		)
		(property "License" "Apache-2.0"
			(at 242.57 196.85 0)
			(effects
				(font
					(size 1.27 1.27)
					(thickness 0.15)
				)
				(justify left bottom)
				(hide yes)
			)
		)
		(pin "1"
		)
		(instances
			(project "jetson-orin-baseboard"
				(path ""
					(reference "#PWR0124")
					(unit 1)
				)
			)
		)
	)
	(symbol
		(lib_name "R_0R_0402_5")
		(lib_id "antmicroResistors0402:R_0R_0402")
		(at 119.38 175.26 0)
		(unit 1)
		(exclude_from_sim no)
		(in_bom no)
		(on_board yes)
		(dnp yes)
		(property "Reference" "R125"
			(at 124.46 174.625 0)
			(effects
				(font
					(size 1.27 1.27)
				)
				(justify left bottom)
			)
		)
		(property "Value" "R_0R_0402"
			(at 139.7 187.96 0)
			(effects
				(font
					(size 1.27 1.27)
					(thickness 0.15)
				)
				(justify left bottom)
				(hide yes)
			)
		)
		(property "Footprint" "antmicro-footprints:R_0402_1005Metric"
			(at 139.7 190.5 0)
			(effects
				(font
					(size 1.27 1.27)
					(thickness 0.15)
				)
				(justify left bottom)
				(hide yes)
			)
		)
		(property "Datasheet" "https://industrial.panasonic.com/cdbs/www-data/pdf/RDA0000/AOA0000C301.pdf"
			(at 139.7 193.04 0)
			(effects
				(font
					(size 1.27 1.27)
					(thickness 0.15)
				)
				(justify left bottom)
				(hide yes)
			)
		)
		(property "Description" ""
			(at 119.38 175.26 0)
			(effects
				(font
					(size 1.27 1.27)
				)
				(hide yes)
			)
		)
		(property "Manufacturer" "Panasonic"
			(at 139.7 198.12 0)
			(effects
				(font
					(size 1.27 1.27)
					(thickness 0.15)
				)
				(justify left bottom)
				(hide yes)
			)
		)
		(property "MPN" "ERJ2GE0R00X"
			(at 139.7 195.58 0)
			(effects
				(font
					(size 1.27 1.27)
					(thickness 0.15)
				)
				(justify left bottom)
				(hide yes)
			)
		)
		(property "Val" "0R"
			(at 116.84 174.625 0)
			(effects
				(font
					(size 1.27 1.27)
					(thickness 0.15)
				)
				(justify left bottom)
			)
		)
		(property "License" "Apache-2.0"
			(at 139.7 200.66 0)
			(effects
				(font
					(size 1.27 1.27)
					(thickness 0.15)
				)
				(justify left bottom)
				(hide yes)
			)
		)
		(property "Author" "Antmicro"
			(at 139.7 203.2 0)
			(effects
				(font
					(size 1.27 1.27)
					(thickness 0.15)
				)
				(justify left bottom)
				(hide yes)
			)
		)
		(property "Tolerance" "~"
			(at 139.7 185.42 0)
			(effects
				(font
					(size 1.27 1.27)
				)
				(justify left bottom)
				(hide yes)
			)
		)
		(property "Current" "1A"
			(at 139.7 205.74 0)
			(effects
				(font
					(size 1.27 1.27)
					(thickness 0.15)
				)
				(justify left bottom)
				(hide yes)
			)
		)
		(pin "1"
		)
		(pin "2"
		)
		(instances
			(project "jetson-orin-baseboard"
				(path ""
					(reference "R125")
					(unit 1)
				)
			)
		)
	)
	(symbol
		(lib_id "antmicroCapacitors0402:C_100n_0402")
		(at 210.82 165.1 180)
		(unit 1)
		(exclude_from_sim no)
		(in_bom yes)
		(on_board yes)
		(dnp no)
		(property "Reference" "C71"
			(at 213.36 163.195 0)
			(effects
				(font
					(size 1.27 1.27)
				)
				(justify left bottom)
			)
		)
		(property "Value" "C_100n_0402"
			(at 190.5 154.94 0)
			(effects
				(font
					(size 1.27 1.27)
					(thickness 0.15)
				)
				(justify left bottom)
				(hide yes)
			)
		)
		(property "Footprint" "antmicro-footprints:C_0402_1005Metric"
			(at 190.5 152.4 0)
			(effects
				(font
					(size 1.27 1.27)
					(thickness 0.15)
				)
				(justify left bottom)
				(hide yes)
			)
		)
		(property "Datasheet" "https://www.murata.com/products/productdetail?partno=GRM155R61H104KE14%23"
			(at 190.5 149.86 0)
			(effects
				(font
					(size 1.27 1.27)
					(thickness 0.15)
				)
				(justify left bottom)
				(hide yes)
			)
		)
		(property "Description" ""
			(at 210.82 165.1 0)
			(effects
				(font
					(size 1.27 1.27)
				)
				(hide yes)
			)
		)
		(property "Manufacturer" "Murata"
			(at 190.5 144.78 0)
			(effects
				(font
					(size 1.27 1.27)
					(thickness 0.15)
				)
				(justify left bottom)
				(hide yes)
			)
		)
		(property "MPN" "GRM155R61H104KE14D"
			(at 190.5 147.32 0)
			(effects
				(font
					(size 1.27 1.27)
					(thickness 0.15)
				)
				(justify left bottom)
				(hide yes)
			)
		)
		(property "Val" "100n"
			(at 207.01 165.735 0)
			(effects
				(font
					(size 1.27 1.27)
					(thickness 0.15)
				)
				(justify left bottom)
			)
		)
		(property "License" "Apache-2.0"
			(at 190.5 142.24 0)
			(effects
				(font
					(size 1.27 1.27)
					(thickness 0.15)
				)
				(justify left bottom)
				(hide yes)
			)
		)
		(property "Author" "Antmicro"
			(at 190.5 139.7 0)
			(effects
				(font
					(size 1.27 1.27)
					(thickness 0.15)
				)
				(justify left bottom)
				(hide yes)
			)
		)
		(property "Voltage" "50V"
			(at 190.5 137.16 0)
			(effects
				(font
					(size 1.27 1.27)
				)
				(justify left bottom)
				(hide yes)
			)
		)
		(property "Dielectric" "X5R"
			(at 190.5 134.62 0)
			(effects
				(font
					(size 1.27 1.27)
				)
				(justify left bottom)
				(hide yes)
			)
		)
		(pin "1"
		)
		(pin "2"
		)
		(instances
			(project "jetson-orin-baseboard"
				(path ""
					(reference "C71")
					(unit 1)
				)
			)
		)
	)
	(symbol
		(lib_id "antmicroTVSDiodes:TPD4E05U06QDQARQ1")
		(at 250.19 185.42 270)
		(unit 1)
		(exclude_from_sim no)
		(in_bom yes)
		(on_board yes)
		(dnp no)
		(property "Reference" "U19"
			(at 245.745 195.58 90)
			(effects
				(font
					(size 1.27 1.27)
				)
			)
		)
		(property "Value" "TPD4E05U06QDQARQ1"
			(at 240.03 209.55 0)
			(effects
				(font
					(size 1.27 1.27)
					(thickness 0.15)
				)
				(justify left bottom)
				(hide yes)
			)
		)
		(property "Footprint" "antmicro-footprints:USON-10_2.5x1mm_P0.5mm"
			(at 245.11 209.55 0)
			(effects
				(font
					(size 1.27 1.27)
					(thickness 0.15)
				)
				(justify left bottom)
				(hide yes)
			)
		)
		(property "Datasheet" "https://www.ti.com/lit/ds/symlink/tpd4e05u06-q1.pdf?HQS=dis-mous-null-mousermode-dsf-pf-null-wwe&ts=1663591265741&ref_url=https%253A%252F%252Fwww.mouser.com%252F"
			(at 242.57 209.55 0)
			(effects
				(font
					(size 1.27 1.27)
					(thickness 0.15)
				)
				(justify left bottom)
				(hide yes)
			)
		)
		(property "Description" ""
			(at 250.19 185.42 0)
			(effects
				(font
					(size 1.27 1.27)
				)
				(hide yes)
			)
		)
		(property "Manufacturer" "Texas Instruments"
			(at 237.49 209.55 0)
			(effects
				(font
					(size 1.27 1.27)
					(thickness 0.15)
				)
				(justify left bottom)
				(hide yes)
			)
		)
		(property "MPN" "TPD4E05U06QDQARQ1"
			(at 245.745 198.12 90)
			(effects
				(font
					(size 1.27 1.27)
					(thickness 0.15)
				)
			)
		)
		(property "Author" "Antmicro"
			(at 234.95 209.55 0)
			(effects
				(font
					(size 1.27 1.27)
					(thickness 0.15)
				)
				(justify left bottom)
				(hide yes)
			)
		)
		(property "License" "Apache-2.0"
			(at 232.41 209.55 0)
			(effects
				(font
					(size 1.27 1.27)
					(thickness 0.15)
				)
				(justify left bottom)
				(hide yes)
			)
		)
		(pin "1"
		)
		(pin "10"
		)
		(pin "2"
		)
		(pin "3"
		)
		(pin "4"
		)
		(pin "5"
		)
		(pin "6"
		)
		(pin "7"
		)
		(pin "8"
		)
		(pin "9"
		)
		(instances
			(project "jetson-orin-baseboard"
				(path ""
					(reference "U19")
					(unit 1)
				)
			)
		)
	)
	(symbol
		(lib_id "antmicroUSBConnectors:USB-C_WE_632723300011")
		(at 289.56 129.54 0)
		(mirror y)
		(unit 1)
		(exclude_from_sim no)
		(in_bom yes)
		(on_board yes)
		(dnp no)
		(property "Reference" "J5"
			(at 302.895 123.19 0)
			(effects
				(font
					(size 1.27 1.27)
				)
			)
		)
		(property "Value" "USB-C_WE_632723300011"
			(at 274.32 137.16 0)
			(effects
				(font
					(size 1.27 1.27)
					(thickness 0.15)
				)
				(justify left bottom)
				(hide yes)
			)
		)
		(property "Footprint" "antmicro-footprints:USB-C_Receptacle_WE_632723300011"
			(at 274.32 139.7 0)
			(effects
				(font
					(size 1.27 1.27)
					(thickness 0.15)
				)
				(justify left bottom)
				(hide yes)
			)
		)
		(property "Datasheet" "https://www.we-online.com/components/products/datasheet/632723300011.pdf"
			(at 274.32 142.24 0)
			(effects
				(font
					(size 1.27 1.27)
					(thickness 0.15)
				)
				(justify left bottom)
				(hide yes)
			)
		)
		(property "Description" ""
			(at 289.56 129.54 0)
			(effects
				(font
					(size 1.27 1.27)
				)
				(hide yes)
			)
		)
		(property "Manufacturer" "Würth Elektronik"
			(at 274.32 144.78 0)
			(effects
				(font
					(size 1.27 1.27)
					(thickness 0.15)
				)
				(justify left bottom)
				(hide yes)
			)
		)
		(property "MPN" "632723300011"
			(at 302.895 125.73 0)
			(effects
				(font
					(size 1.27 1.27)
					(thickness 0.15)
				)
			)
		)
		(property "Author" "Antmicro"
			(at 274.32 147.32 0)
			(effects
				(font
					(size 1.27 1.27)
					(thickness 0.15)
				)
				(justify left bottom)
				(hide yes)
			)
		)
		(property "License" "Apache-2.0"
			(at 274.32 149.86 0)
			(effects
				(font
					(size 1.27 1.27)
					(thickness 0.15)
				)
				(justify left bottom)
				(hide yes)
			)
		)
		(pin "A1"
		)
		(pin "A10"
		)
		(pin "A11"
		)
		(pin "A12"
		)
		(pin "A2"
		)
		(pin "A3"
		)
		(pin "A4"
		)
		(pin "A5"
		)
		(pin "A6"
		)
		(pin "A7"
		)
		(pin "A8"
		)
		(pin "A9"
		)
		(pin "B1"
		)
		(pin "B10"
		)
		(pin "B11"
		)
		(pin "B12"
		)
		(pin "B2"
		)
		(pin "B3"
		)
		(pin "B4"
		)
		(pin "B5"
		)
		(pin "B6"
		)
		(pin "B7"
		)
		(pin "B8"
		)
		(pin "B9"
		)
		(pin "SH"
		)
		(instances
			(project "jetson-orin-baseboard"
				(path ""
					(reference "J5")
					(unit 1)
				)
			)
		)
	)
	(symbol
		(lib_name "GND_3")
		(lib_id "antmicropower:GND")
		(at 151.13 109.22 0)
		(unit 1)
		(exclude_from_sim no)
		(in_bom yes)
		(on_board yes)
		(dnp no)
		(property "Reference" "#PWR0117"
			(at 151.13 115.57 0)
			(effects
				(font
					(size 1.27 1.27)
				)
				(justify left bottom)
				(hide yes)
			)
		)
		(property "Value" "GND"
			(at 151.13 113.03 0)
			(effects
				(font
					(size 1.27 1.27)
					(thickness 0.15)
				)
			)
		)
		(property "Footprint" ""
			(at 160.02 116.84 0)
			(effects
				(font
					(size 1.27 1.27)
					(thickness 0.15)
				)
				(justify left bottom)
				(hide yes)
			)
		)
		(property "Datasheet" ""
			(at 160.02 121.92 0)
			(effects
				(font
					(size 1.27 1.27)
					(thickness 0.15)
				)
				(justify left bottom)
				(hide yes)
			)
		)
		(property "Description" ""
			(at 151.13 109.22 0)
			(effects
				(font
					(size 1.27 1.27)
				)
				(hide yes)
			)
		)
		(property "Author" "Antmicro"
			(at 160.02 116.84 0)
			(effects
				(font
					(size 1.27 1.27)
					(thickness 0.15)
				)
				(justify left bottom)
				(hide yes)
			)
		)
		(property "License" "Apache-2.0"
			(at 160.02 119.38 0)
			(effects
				(font
					(size 1.27 1.27)
					(thickness 0.15)
				)
				(justify left bottom)
				(hide yes)
			)
		)
		(pin "1"
		)
		(instances
			(project "jetson-orin-baseboard"
				(path ""
					(reference "#PWR0117")
					(unit 1)
				)
			)
		)
	)
	(symbol
		(lib_id "antmicroResistors0402:R_200k_0402")
		(at 189.23 114.3 90)
		(unit 1)
		(exclude_from_sim no)
		(in_bom yes)
		(on_board yes)
		(dnp no)
		(property "Reference" "R126"
			(at 190.5 110.49 90)
			(effects
				(font
					(size 1.27 1.27)
				)
				(justify right)
			)
		)
		(property "Value" "R_200k_0402"
			(at 201.93 93.98 0)
			(effects
				(font
					(size 1.27 1.27)
					(thickness 0.15)
				)
				(justify left bottom)
				(hide yes)
			)
		)
		(property "Footprint" "antmicro-footprints:R_0402_1005Metric"
			(at 204.47 93.98 0)
			(effects
				(font
					(size 1.27 1.27)
					(thickness 0.15)
				)
				(justify left bottom)
				(hide yes)
			)
		)
		(property "Datasheet" "https://www.bourns.com/docs/product-datasheets/cr.pdf"
			(at 207.01 93.98 0)
			(effects
				(font
					(size 1.27 1.27)
					(thickness 0.15)
				)
				(justify left bottom)
				(hide yes)
			)
		)
		(property "Description" ""
			(at 189.23 114.3 0)
			(effects
				(font
					(size 1.27 1.27)
				)
				(hide yes)
			)
		)
		(property "Manufacturer" "Bourns"
			(at 212.09 93.98 0)
			(effects
				(font
					(size 1.27 1.27)
					(thickness 0.15)
				)
				(justify left bottom)
				(hide yes)
			)
		)
		(property "MPN" "CR0402-FX-2003GLF"
			(at 209.55 93.98 0)
			(effects
				(font
					(size 1.27 1.27)
					(thickness 0.15)
				)
				(justify left bottom)
				(hide yes)
			)
		)
		(property "Val" "200k"
			(at 190.5 113.03 90)
			(effects
				(font
					(size 1.27 1.27)
					(thickness 0.15)
				)
				(justify right)
			)
		)
		(property "License" "Apache-2.0"
			(at 214.63 93.98 0)
			(effects
				(font
					(size 1.27 1.27)
					(thickness 0.15)
				)
				(justify left bottom)
				(hide yes)
			)
		)
		(property "Author" "Antmicro"
			(at 217.17 93.98 0)
			(effects
				(font
					(size 1.27 1.27)
					(thickness 0.15)
				)
				(justify left bottom)
				(hide yes)
			)
		)
		(property "Tolerance" "1%"
			(at 199.39 93.98 0)
			(effects
				(font
					(size 1.27 1.27)
				)
				(justify left bottom)
				(hide yes)
			)
		)
		(pin "1"
		)
		(pin "2"
		)
		(instances
			(project "jetson-orin-baseboard"
				(path ""
					(reference "R126")
					(unit 1)
				)
			)
		)
	)
	(symbol
		(lib_id "antmicroTVSDiodes:TPD4E05U06QDQARQ1")
		(at 276.86 185.42 270)
		(unit 1)
		(exclude_from_sim no)
		(in_bom yes)
		(on_board yes)
		(dnp no)
		(property "Reference" "U20"
			(at 272.415 195.58 90)
			(effects
				(font
					(size 1.27 1.27)
				)
			)
		)
		(property "Value" "TPD4E05U06QDQARQ1"
			(at 266.7 209.55 0)
			(effects
				(font
					(size 1.27 1.27)
					(thickness 0.15)
				)
				(justify left bottom)
				(hide yes)
			)
		)
		(property "Footprint" "antmicro-footprints:USON-10_2.5x1mm_P0.5mm"
			(at 271.78 209.55 0)
			(effects
				(font
					(size 1.27 1.27)
					(thickness 0.15)
				)
				(justify left bottom)
				(hide yes)
			)
		)
		(property "Datasheet" "https://www.ti.com/lit/ds/symlink/tpd4e05u06-q1.pdf?HQS=dis-mous-null-mousermode-dsf-pf-null-wwe&ts=1663591265741&ref_url=https%253A%252F%252Fwww.mouser.com%252F"
			(at 269.24 209.55 0)
			(effects
				(font
					(size 1.27 1.27)
					(thickness 0.15)
				)
				(justify left bottom)
				(hide yes)
			)
		)
		(property "Description" ""
			(at 276.86 185.42 0)
			(effects
				(font
					(size 1.27 1.27)
				)
				(hide yes)
			)
		)
		(property "Manufacturer" "Texas Instruments"
			(at 264.16 209.55 0)
			(effects
				(font
					(size 1.27 1.27)
					(thickness 0.15)
				)
				(justify left bottom)
				(hide yes)
			)
		)
		(property "MPN" "TPD4E05U06QDQARQ1"
			(at 272.415 198.12 90)
			(effects
				(font
					(size 1.27 1.27)
					(thickness 0.15)
				)
			)
		)
		(property "Author" "Antmicro"
			(at 261.62 209.55 0)
			(effects
				(font
					(size 1.27 1.27)
					(thickness 0.15)
				)
				(justify left bottom)
				(hide yes)
			)
		)
		(property "License" "Apache-2.0"
			(at 259.08 209.55 0)
			(effects
				(font
					(size 1.27 1.27)
					(thickness 0.15)
				)
				(justify left bottom)
				(hide yes)
			)
		)
		(pin "1"
		)
		(pin "10"
		)
		(pin "2"
		)
		(pin "3"
		)
		(pin "4"
		)
		(pin "5"
		)
		(pin "6"
		)
		(pin "7"
		)
		(pin "8"
		)
		(pin "9"
		)
		(instances
			(project "jetson-orin-baseboard"
				(path ""
					(reference "U20")
					(unit 1)
				)
			)
		)
	)
	(symbol
		(lib_name "GND_3")
		(lib_id "antmicropower:GND")
		(at 113.03 143.51 0)
		(unit 1)
		(exclude_from_sim no)
		(in_bom yes)
		(on_board yes)
		(dnp no)
		(property "Reference" "#PWR0111"
			(at 113.03 149.86 0)
			(effects
				(font
					(size 1.27 1.27)
				)
				(justify left bottom)
				(hide yes)
			)
		)
		(property "Value" "GND"
			(at 113.03 147.32 0)
			(effects
				(font
					(size 1.27 1.27)
					(thickness 0.15)
				)
			)
		)
		(property "Footprint" ""
			(at 121.92 151.13 0)
			(effects
				(font
					(size 1.27 1.27)
					(thickness 0.15)
				)
				(justify left bottom)
				(hide yes)
			)
		)
		(property "Datasheet" ""
			(at 121.92 156.21 0)
			(effects
				(font
					(size 1.27 1.27)
					(thickness 0.15)
				)
				(justify left bottom)
				(hide yes)
			)
		)
		(property "Description" ""
			(at 113.03 143.51 0)
			(effects
				(font
					(size 1.27 1.27)
				)
				(hide yes)
			)
		)
		(property "Author" "Antmicro"
			(at 121.92 151.13 0)
			(effects
				(font
					(size 1.27 1.27)
					(thickness 0.15)
				)
				(justify left bottom)
				(hide yes)
			)
		)
		(property "License" "Apache-2.0"
			(at 121.92 153.67 0)
			(effects
				(font
					(size 1.27 1.27)
					(thickness 0.15)
				)
				(justify left bottom)
				(hide yes)
			)
		)
		(pin "1"
		)
		(instances
			(project "jetson-orin-baseboard"
				(path ""
					(reference "#PWR0111")
					(unit 1)
				)
			)
		)
	)
	(symbol
		(lib_name "+5V_2")
		(lib_id "antmicropower:+5V")
		(at 81.28 173.99 0)
		(unit 1)
		(exclude_from_sim no)
		(in_bom yes)
		(on_board yes)
		(dnp no)
		(property "Reference" "#PWR0108"
			(at 81.28 177.8 0)
			(effects
				(font
					(size 1.27 1.27)
				)
				(justify left bottom)
				(hide yes)
			)
		)
		(property "Value" "+5V"
			(at 79.375 170.18 0)
			(effects
				(font
					(size 1.27 1.27)
					(thickness 0.15)
				)
				(justify left)
			)
		)
		(property "Footprint" ""
			(at 96.52 181.61 0)
			(effects
				(font
					(size 1.27 1.27)
					(thickness 0.15)
				)
				(justify left bottom)
				(hide yes)
			)
		)
		(property "Datasheet" ""
			(at 96.52 184.15 0)
			(effects
				(font
					(size 1.27 1.27)
					(thickness 0.15)
				)
				(justify left bottom)
				(hide yes)
			)
		)
		(property "Description" ""
			(at 81.28 173.99 0)
			(effects
				(font
					(size 1.27 1.27)
				)
				(hide yes)
			)
		)
		(property "Author" "Antmicro"
			(at 96.52 181.61 0)
			(effects
				(font
					(size 1.27 1.27)
					(thickness 0.15)
				)
				(justify left bottom)
				(hide yes)
			)
		)
		(property "License" "Apache-2.0"
			(at 96.52 184.15 0)
			(effects
				(font
					(size 1.27 1.27)
					(thickness 0.15)
				)
				(justify left bottom)
				(hide yes)
			)
		)
		(pin "1"
		)
		(instances
			(project "jetson-orin-baseboard"
				(path ""
					(reference "#PWR0108")
					(unit 1)
				)
			)
		)
	)
	(symbol
		(lib_id "antmicroResistors0402:R_0R_0402")
		(at 330.2 69.85 0)
		(unit 1)
		(exclude_from_sim no)
		(in_bom no)
		(on_board yes)
		(dnp yes)
		(property "Reference" "R23"
			(at 335.28 69.215 0)
			(effects
				(font
					(size 1.27 1.27)
				)
				(justify left bottom)
			)
		)
		(property "Value" "R_0R_0402"
			(at 350.52 82.55 0)
			(effects
				(font
					(size 1.27 1.27)
					(thickness 0.15)
				)
				(justify left bottom)
				(hide yes)
			)
		)
		(property "Footprint" "antmicro-footprints:R_0402_1005Metric"
			(at 350.52 85.09 0)
			(effects
				(font
					(size 1.27 1.27)
					(thickness 0.15)
				)
				(justify left bottom)
				(hide yes)
			)
		)
		(property "Datasheet" "https://industrial.panasonic.com/cdbs/www-data/pdf/RDA0000/AOA0000C301.pdf"
			(at 350.52 87.63 0)
			(effects
				(font
					(size 1.27 1.27)
					(thickness 0.15)
				)
				(justify left bottom)
				(hide yes)
			)
		)
		(property "Description" ""
			(at 330.2 69.85 0)
			(effects
				(font
					(size 1.27 1.27)
				)
				(hide yes)
			)
		)
		(property "Manufacturer" "Panasonic"
			(at 350.52 92.71 0)
			(effects
				(font
					(size 1.27 1.27)
					(thickness 0.15)
				)
				(justify left bottom)
				(hide yes)
			)
		)
		(property "MPN" "ERJ2GE0R00X"
			(at 350.52 90.17 0)
			(effects
				(font
					(size 1.27 1.27)
					(thickness 0.15)
				)
				(justify left bottom)
				(hide yes)
			)
		)
		(property "Val" "0R"
			(at 327.66 69.215 0)
			(effects
				(font
					(size 1.27 1.27)
					(thickness 0.15)
				)
				(justify left bottom)
			)
		)
		(property "License" "Apache-2.0"
			(at 350.52 95.25 0)
			(effects
				(font
					(size 1.27 1.27)
					(thickness 0.15)
				)
				(justify left bottom)
				(hide yes)
			)
		)
		(property "Author" "Antmicro"
			(at 350.52 97.79 0)
			(effects
				(font
					(size 1.27 1.27)
					(thickness 0.15)
				)
				(justify left bottom)
				(hide yes)
			)
		)
		(property "Tolerance" "~"
			(at 350.52 80.01 0)
			(effects
				(font
					(size 1.27 1.27)
				)
				(justify left bottom)
				(hide yes)
			)
		)
		(property "Current" "1A"
			(at 350.52 100.33 0)
			(effects
				(font
					(size 1.27 1.27)
					(thickness 0.15)
				)
				(justify left bottom)
				(hide yes)
			)
		)
		(pin "1"
		)
		(pin "2"
		)
		(instances
			(project "jetson-orin-baseboard"
				(path ""
					(reference "R23")
					(unit 1)
				)
			)
		)
	)
	(symbol
		(lib_id "antmicroCapacitors0402:C_100n_0402")
		(at 210.82 180.34 180)
		(unit 1)
		(exclude_from_sim no)
		(in_bom yes)
		(on_board yes)
		(dnp no)
		(property "Reference" "C72"
			(at 213.36 178.435 0)
			(effects
				(font
					(size 1.27 1.27)
				)
				(justify left bottom)
			)
		)
		(property "Value" "C_100n_0402"
			(at 190.5 170.18 0)
			(effects
				(font
					(size 1.27 1.27)
					(thickness 0.15)
				)
				(justify left bottom)
				(hide yes)
			)
		)
		(property "Footprint" "antmicro-footprints:C_0402_1005Metric"
			(at 190.5 167.64 0)
			(effects
				(font
					(size 1.27 1.27)
					(thickness 0.15)
				)
				(justify left bottom)
				(hide yes)
			)
		)
		(property "Datasheet" "https://www.murata.com/products/productdetail?partno=GRM155R61H104KE14%23"
			(at 190.5 165.1 0)
			(effects
				(font
					(size 1.27 1.27)
					(thickness 0.15)
				)
				(justify left bottom)
				(hide yes)
			)
		)
		(property "Description" ""
			(at 210.82 180.34 0)
			(effects
				(font
					(size 1.27 1.27)
				)
				(hide yes)
			)
		)
		(property "Manufacturer" "Murata"
			(at 190.5 160.02 0)
			(effects
				(font
					(size 1.27 1.27)
					(thickness 0.15)
				)
				(justify left bottom)
				(hide yes)
			)
		)
		(property "MPN" "GRM155R61H104KE14D"
			(at 190.5 162.56 0)
			(effects
				(font
					(size 1.27 1.27)
					(thickness 0.15)
				)
				(justify left bottom)
				(hide yes)
			)
		)
		(property "Val" "100n"
			(at 207.01 180.975 0)
			(effects
				(font
					(size 1.27 1.27)
					(thickness 0.15)
				)
				(justify left bottom)
			)
		)
		(property "License" "Apache-2.0"
			(at 190.5 157.48 0)
			(effects
				(font
					(size 1.27 1.27)
					(thickness 0.15)
				)
				(justify left bottom)
				(hide yes)
			)
		)
		(property "Author" "Antmicro"
			(at 190.5 154.94 0)
			(effects
				(font
					(size 1.27 1.27)
					(thickness 0.15)
				)
				(justify left bottom)
				(hide yes)
			)
		)
		(property "Voltage" "50V"
			(at 190.5 152.4 0)
			(effects
				(font
					(size 1.27 1.27)
				)
				(justify left bottom)
				(hide yes)
			)
		)
		(property "Dielectric" "X5R"
			(at 190.5 149.86 0)
			(effects
				(font
					(size 1.27 1.27)
				)
				(justify left bottom)
				(hide yes)
			)
		)
		(pin "1"
		)
		(pin "2"
		)
		(instances
			(project "jetson-orin-baseboard"
				(path ""
					(reference "C72")
					(unit 1)
				)
			)
		)
	)
	(symbol
		(lib_id "antmicropower:+3V3")
		(at 189.23 107.95 0)
		(mirror y)
		(unit 1)
		(exclude_from_sim no)
		(in_bom yes)
		(on_board yes)
		(dnp no)
		(property "Reference" "#PWR0119"
			(at 189.23 111.76 0)
			(effects
				(font
					(size 1.27 1.27)
				)
				(justify left bottom)
				(hide yes)
			)
		)
		(property "Value" "+3V3"
			(at 186.055 104.14 0)
			(effects
				(font
					(size 1.27 1.27)
					(thickness 0.15)
				)
				(justify right)
			)
		)
		(property "Footprint" ""
			(at 173.99 115.57 0)
			(effects
				(font
					(size 1.27 1.27)
					(thickness 0.15)
				)
				(justify left bottom)
				(hide yes)
			)
		)
		(property "Datasheet" ""
			(at 173.99 118.11 0)
			(effects
				(font
					(size 1.27 1.27)
					(thickness 0.15)
				)
				(justify left bottom)
				(hide yes)
			)
		)
		(property "Description" ""
			(at 189.23 107.95 0)
			(effects
				(font
					(size 1.27 1.27)
				)
				(hide yes)
			)
		)
		(property "Author" "Antmicro"
			(at 173.99 110.49 0)
			(effects
				(font
					(size 1.27 1.27)
					(thickness 0.15)
				)
				(justify left bottom)
				(hide yes)
			)
		)
		(property "License" "Apache-2.0"
			(at 173.99 113.03 0)
			(effects
				(font
					(size 1.27 1.27)
					(thickness 0.15)
				)
				(justify left bottom)
				(hide yes)
			)
		)
		(pin "1"
		)
		(instances
			(project "jetson-orin-baseboard"
				(path ""
					(reference "#PWR0119")
					(unit 1)
				)
			)
		)
	)
	(symbol
		(lib_name "R_0R_0402_6")
		(lib_id "antmicroResistors0402:R_0R_0402")
		(at 81.28 180.34 90)
		(unit 1)
		(exclude_from_sim no)
		(in_bom no)
		(on_board yes)
		(dnp yes)
		(property "Reference" "R113"
			(at 82.55 176.53 90)
			(effects
				(font
					(size 1.27 1.27)
				)
				(justify right)
			)
		)
		(property "Value" "R_0R_0402"
			(at 93.98 160.02 0)
			(effects
				(font
					(size 1.27 1.27)
					(thickness 0.15)
				)
				(justify left bottom)
				(hide yes)
			)
		)
		(property "Footprint" "antmicro-footprints:R_0402_1005Metric"
			(at 96.52 160.02 0)
			(effects
				(font
					(size 1.27 1.27)
					(thickness 0.15)
				)
				(justify left bottom)
				(hide yes)
			)
		)
		(property "Datasheet" "https://industrial.panasonic.com/cdbs/www-data/pdf/RDA0000/AOA0000C301.pdf"
			(at 99.06 160.02 0)
			(effects
				(font
					(size 1.27 1.27)
					(thickness 0.15)
				)
				(justify left bottom)
				(hide yes)
			)
		)
		(property "Description" ""
			(at 81.28 180.34 0)
			(effects
				(font
					(size 1.27 1.27)
				)
				(hide yes)
			)
		)
		(property "Manufacturer" "Panasonic"
			(at 104.14 160.02 0)
			(effects
				(font
					(size 1.27 1.27)
					(thickness 0.15)
				)
				(justify left bottom)
				(hide yes)
			)
		)
		(property "MPN" "ERJ2GE0R00X"
			(at 101.6 160.02 0)
			(effects
				(font
					(size 1.27 1.27)
					(thickness 0.15)
				)
				(justify left bottom)
				(hide yes)
			)
		)
		(property "Val" "0R"
			(at 82.55 179.07 90)
			(effects
				(font
					(size 1.27 1.27)
					(thickness 0.15)
				)
				(justify right)
			)
		)
		(property "License" "Apache-2.0"
			(at 106.68 160.02 0)
			(effects
				(font
					(size 1.27 1.27)
					(thickness 0.15)
				)
				(justify left bottom)
				(hide yes)
			)
		)
		(property "Author" "Antmicro"
			(at 109.22 160.02 0)
			(effects
				(font
					(size 1.27 1.27)
					(thickness 0.15)
				)
				(justify left bottom)
				(hide yes)
			)
		)
		(property "Tolerance" "~"
			(at 91.44 160.02 0)
			(effects
				(font
					(size 1.27 1.27)
				)
				(justify left bottom)
				(hide yes)
			)
		)
		(property "Current" "1A"
			(at 111.76 160.02 0)
			(effects
				(font
					(size 1.27 1.27)
					(thickness 0.15)
				)
				(justify left bottom)
				(hide yes)
			)
		)
		(pin "1"
		)
		(pin "2"
		)
		(instances
			(project "jetson-orin-baseboard"
				(path ""
					(reference "R113")
					(unit 1)
				)
			)
		)
	)
	(symbol
		(lib_name "R_0R_0402_7")
		(lib_id "antmicroResistors0402:R_0R_0402")
		(at 119.38 177.8 0)
		(unit 1)
		(exclude_from_sim no)
		(in_bom no)
		(on_board yes)
		(dnp yes)
		(property "Reference" "R245"
			(at 124.46 177.165 0)
			(effects
				(font
					(size 1.27 1.27)
				)
				(justify left bottom)
			)
		)
		(property "Value" "R_0R_0402"
			(at 139.7 190.5 0)
			(effects
				(font
					(size 1.27 1.27)
					(thickness 0.15)
				)
				(justify left bottom)
				(hide yes)
			)
		)
		(property "Footprint" "antmicro-footprints:R_0402_1005Metric"
			(at 139.7 193.04 0)
			(effects
				(font
					(size 1.27 1.27)
					(thickness 0.15)
				)
				(justify left bottom)
				(hide yes)
			)
		)
		(property "Datasheet" "https://industrial.panasonic.com/cdbs/www-data/pdf/RDA0000/AOA0000C301.pdf"
			(at 139.7 195.58 0)
			(effects
				(font
					(size 1.27 1.27)
					(thickness 0.15)
				)
				(justify left bottom)
				(hide yes)
			)
		)
		(property "Description" ""
			(at 119.38 177.8 0)
			(effects
				(font
					(size 1.27 1.27)
				)
				(hide yes)
			)
		)
		(property "Manufacturer" "Panasonic"
			(at 139.7 200.66 0)
			(effects
				(font
					(size 1.27 1.27)
					(thickness 0.15)
				)
				(justify left bottom)
				(hide yes)
			)
		)
		(property "MPN" "ERJ2GE0R00X"
			(at 139.7 198.12 0)
			(effects
				(font
					(size 1.27 1.27)
					(thickness 0.15)
				)
				(justify left bottom)
				(hide yes)
			)
		)
		(property "Val" "0R"
			(at 116.84 177.165 0)
			(effects
				(font
					(size 1.27 1.27)
					(thickness 0.15)
				)
				(justify left bottom)
			)
		)
		(property "License" "Apache-2.0"
			(at 139.7 203.2 0)
			(effects
				(font
					(size 1.27 1.27)
					(thickness 0.15)
				)
				(justify left bottom)
				(hide yes)
			)
		)
		(property "Author" "Antmicro"
			(at 139.7 205.74 0)
			(effects
				(font
					(size 1.27 1.27)
					(thickness 0.15)
				)
				(justify left bottom)
				(hide yes)
			)
		)
		(property "Tolerance" "~"
			(at 139.7 187.96 0)
			(effects
				(font
					(size 1.27 1.27)
				)
				(justify left bottom)
				(hide yes)
			)
		)
		(property "Current" "1A"
			(at 139.7 208.28 0)
			(effects
				(font
					(size 1.27 1.27)
					(thickness 0.15)
				)
				(justify left bottom)
				(hide yes)
			)
		)
		(pin "1"
		)
		(pin "2"
		)
		(instances
			(project "jetson-orin-baseboard"
				(path ""
					(reference "R245")
					(unit 1)
				)
			)
		)
	)
	(symbol
		(lib_id "antmicroResistors0402:R_1k_0402")
		(at 204.47 83.82 90)
		(unit 1)
		(exclude_from_sim no)
		(in_bom yes)
		(on_board yes)
		(dnp no)
		(property "Reference" "R184"
			(at 205.74 80.01 90)
			(effects
				(font
					(size 1.27 1.27)
				)
				(justify right)
			)
		)
		(property "Value" "R_1k_0402"
			(at 217.17 63.5 0)
			(effects
				(font
					(size 1.27 1.27)
					(thickness 0.15)
				)
				(justify left bottom)
				(hide yes)
			)
		)
		(property "Footprint" "antmicro-footprints:R_0402_1005Metric"
			(at 219.71 63.5 0)
			(effects
				(font
					(size 1.27 1.27)
					(thickness 0.15)
				)
				(justify left bottom)
				(hide yes)
			)
		)
		(property "Datasheet" "https://www.bourns.com/docs/product-datasheets/cr.pdf"
			(at 222.25 63.5 0)
			(effects
				(font
					(size 1.27 1.27)
					(thickness 0.15)
				)
				(justify left bottom)
				(hide yes)
			)
		)
		(property "Description" ""
			(at 204.47 83.82 0)
			(effects
				(font
					(size 1.27 1.27)
				)
				(hide yes)
			)
		)
		(property "Manufacturer" "Bourns"
			(at 227.33 63.5 0)
			(effects
				(font
					(size 1.27 1.27)
					(thickness 0.15)
				)
				(justify left bottom)
				(hide yes)
			)
		)
		(property "MPN" "CR0402-FX-1001GLF"
			(at 224.79 63.5 0)
			(effects
				(font
					(size 1.27 1.27)
					(thickness 0.15)
				)
				(justify left bottom)
				(hide yes)
			)
		)
		(property "Val" "1k"
			(at 205.74 82.55 90)
			(effects
				(font
					(size 1.27 1.27)
					(thickness 0.15)
				)
				(justify right)
			)
		)
		(property "License" "Apache-2.0"
			(at 229.87 63.5 0)
			(effects
				(font
					(size 1.27 1.27)
					(thickness 0.15)
				)
				(justify left bottom)
				(hide yes)
			)
		)
		(property "Author" "Antmicro"
			(at 232.41 63.5 0)
			(effects
				(font
					(size 1.27 1.27)
					(thickness 0.15)
				)
				(justify left bottom)
				(hide yes)
			)
		)
		(property "Tolerance" "1%"
			(at 214.63 63.5 0)
			(effects
				(font
					(size 1.27 1.27)
				)
				(justify left bottom)
				(hide yes)
			)
		)
		(pin "1"
		)
		(pin "2"
		)
		(instances
			(project "jetson-orin-baseboard"
				(path ""
					(reference "R184")
					(unit 1)
				)
			)
		)
	)
	(symbol
		(lib_name "GND_3")
		(lib_id "antmicropower:GND")
		(at 260.35 186.69 0)
		(unit 1)
		(exclude_from_sim no)
		(in_bom yes)
		(on_board yes)
		(dnp no)
		(property "Reference" "#PWR0126"
			(at 260.35 193.04 0)
			(effects
				(font
					(size 1.27 1.27)
				)
				(justify left bottom)
				(hide yes)
			)
		)
		(property "Value" "GND"
			(at 260.35 190.5 0)
			(effects
				(font
					(size 1.27 1.27)
					(thickness 0.15)
				)
			)
		)
		(property "Footprint" ""
			(at 269.24 194.31 0)
			(effects
				(font
					(size 1.27 1.27)
					(thickness 0.15)
				)
				(justify left bottom)
				(hide yes)
			)
		)
		(property "Datasheet" ""
			(at 269.24 199.39 0)
			(effects
				(font
					(size 1.27 1.27)
					(thickness 0.15)
				)
				(justify left bottom)
				(hide yes)
			)
		)
		(property "Description" ""
			(at 260.35 186.69 0)
			(effects
				(font
					(size 1.27 1.27)
				)
				(hide yes)
			)
		)
		(property "Author" "Antmicro"
			(at 269.24 194.31 0)
			(effects
				(font
					(size 1.27 1.27)
					(thickness 0.15)
				)
				(justify left bottom)
				(hide yes)
			)
		)
		(property "License" "Apache-2.0"
			(at 269.24 196.85 0)
			(effects
				(font
					(size 1.27 1.27)
					(thickness 0.15)
				)
				(justify left bottom)
				(hide yes)
			)
		)
		(pin "1"
		)
		(instances
			(project "jetson-orin-baseboard"
				(path ""
					(reference "#PWR0126")
					(unit 1)
				)
			)
		)
	)
	(symbol
		(lib_name "R_0R_0402_8")
		(lib_id "antmicroResistors0402:R_0R_0402")
		(at 119.38 154.94 0)
		(unit 1)
		(exclude_from_sim no)
		(in_bom yes)
		(on_board yes)
		(dnp no)
		(property "Reference" "R200"
			(at 124.46 154.305 0)
			(effects
				(font
					(size 1.27 1.27)
				)
				(justify left bottom)
			)
		)
		(property "Value" "R_0R_0402"
			(at 139.7 167.64 0)
			(effects
				(font
					(size 1.27 1.27)
					(thickness 0.15)
				)
				(justify left bottom)
				(hide yes)
			)
		)
		(property "Footprint" "antmicro-footprints:R_0402_1005Metric"
			(at 139.7 170.18 0)
			(effects
				(font
					(size 1.27 1.27)
					(thickness 0.15)
				)
				(justify left bottom)
				(hide yes)
			)
		)
		(property "Datasheet" "https://industrial.panasonic.com/cdbs/www-data/pdf/RDA0000/AOA0000C301.pdf"
			(at 139.7 172.72 0)
			(effects
				(font
					(size 1.27 1.27)
					(thickness 0.15)
				)
				(justify left bottom)
				(hide yes)
			)
		)
		(property "Description" ""
			(at 119.38 154.94 0)
			(effects
				(font
					(size 1.27 1.27)
				)
				(hide yes)
			)
		)
		(property "Manufacturer" "Panasonic"
			(at 139.7 177.8 0)
			(effects
				(font
					(size 1.27 1.27)
					(thickness 0.15)
				)
				(justify left bottom)
				(hide yes)
			)
		)
		(property "MPN" "ERJ2GE0R00X"
			(at 139.7 175.26 0)
			(effects
				(font
					(size 1.27 1.27)
					(thickness 0.15)
				)
				(justify left bottom)
				(hide yes)
			)
		)
		(property "Val" "0R"
			(at 116.84 154.305 0)
			(effects
				(font
					(size 1.27 1.27)
					(thickness 0.15)
				)
				(justify left bottom)
			)
		)
		(property "License" "Apache-2.0"
			(at 139.7 180.34 0)
			(effects
				(font
					(size 1.27 1.27)
					(thickness 0.15)
				)
				(justify left bottom)
				(hide yes)
			)
		)
		(property "Author" "Antmicro"
			(at 139.7 182.88 0)
			(effects
				(font
					(size 1.27 1.27)
					(thickness 0.15)
				)
				(justify left bottom)
				(hide yes)
			)
		)
		(property "Tolerance" "~"
			(at 139.7 165.1 0)
			(effects
				(font
					(size 1.27 1.27)
				)
				(justify left bottom)
				(hide yes)
			)
		)
		(property "Current" "1A"
			(at 139.7 185.42 0)
			(effects
				(font
					(size 1.27 1.27)
					(thickness 0.15)
				)
				(justify left bottom)
				(hide yes)
			)
		)
		(pin "1"
		)
		(pin "2"
		)
		(instances
			(project "jetson-orin-baseboard"
				(path ""
					(reference "R200")
					(unit 1)
				)
			)
		)
	)
	(symbol
		(lib_id "antmicroResistors0402:R_887k_0402")
		(at 208.28 129.54 0)
		(unit 1)
		(exclude_from_sim no)
		(in_bom yes)
		(on_board yes)
		(dnp no)
		(property "Reference" "R128"
			(at 213.36 128.905 0)
			(effects
				(font
					(size 1.27 1.27)
					(thickness 0.15)
				)
				(justify left bottom)
			)
		)
		(property "Value" "R_887k_0402"
			(at 228.6 142.24 0)
			(effects
				(font
					(size 1.27 1.27)
					(thickness 0.15)
				)
				(justify left bottom)
				(hide yes)
			)
		)
		(property "Footprint" "antmicro-footprints:R_0402_1005Metric"
			(at 228.6 144.78 0)
			(effects
				(font
					(size 1.27 1.27)
					(thickness 0.15)
				)
				(justify left bottom)
				(hide yes)
			)
		)
		(property "Datasheet" "https://eu.mouser.com/datasheet/2/315/AOA0000C304-1149620.pdf"
			(at 228.6 147.32 0)
			(effects
				(font
					(size 1.27 1.27)
					(thickness 0.15)
				)
				(justify left bottom)
				(hide yes)
			)
		)
		(property "Description" ""
			(at 208.28 129.54 0)
			(effects
				(font
					(size 1.27 1.27)
				)
				(hide yes)
			)
		)
		(property "MPN" "ERJ-2RKF8873X"
			(at 228.6 149.86 0)
			(effects
				(font
					(size 1.27 1.27)
					(thickness 0.15)
				)
				(justify left bottom)
				(hide yes)
			)
		)
		(property "Manufacturer" "Panasonic"
			(at 228.6 152.4 0)
			(effects
				(font
					(size 1.27 1.27)
					(thickness 0.15)
				)
				(justify left bottom)
				(hide yes)
			)
		)
		(property "License" "Apache-2.0"
			(at 228.6 154.94 0)
			(effects
				(font
					(size 1.27 1.27)
					(thickness 0.15)
				)
				(justify left bottom)
				(hide yes)
			)
		)
		(property "Author" "Antmicro"
			(at 228.6 157.48 0)
			(effects
				(font
					(size 1.27 1.27)
					(thickness 0.15)
				)
				(justify left bottom)
				(hide yes)
			)
		)
		(property "Val" "887k"
			(at 203.2 128.905 0)
			(effects
				(font
					(size 1.27 1.27)
					(thickness 0.15)
				)
				(justify left bottom)
			)
		)
		(property "Tolerance" "1%"
			(at 228.6 139.7 0)
			(effects
				(font
					(size 1.27 1.27)
				)
				(justify left bottom)
				(hide yes)
			)
		)
		(pin "2"
		)
		(pin "1"
		)
		(instances
			(project "jetson-orin-baseboard"
				(path ""
					(reference "R128")
					(unit 1)
				)
			)
		)
	)
	(symbol
		(lib_name "GND_3")
		(lib_id "antmicropower:GND")
		(at 345.44 87.63 0)
		(unit 1)
		(exclude_from_sim no)
		(in_bom yes)
		(on_board yes)
		(dnp no)
		(property "Reference" "#PWR0274"
			(at 345.44 93.98 0)
			(effects
				(font
					(size 1.27 1.27)
				)
				(justify left bottom)
				(hide yes)
			)
		)
		(property "Value" "GND"
			(at 345.44 91.44 0)
			(effects
				(font
					(size 1.27 1.27)
					(thickness 0.15)
				)
			)
		)
		(property "Footprint" ""
			(at 354.33 95.25 0)
			(effects
				(font
					(size 1.27 1.27)
					(thickness 0.15)
				)
				(justify left bottom)
				(hide yes)
			)
		)
		(property "Datasheet" ""
			(at 354.33 100.33 0)
			(effects
				(font
					(size 1.27 1.27)
					(thickness 0.15)
				)
				(justify left bottom)
				(hide yes)
			)
		)
		(property "Description" ""
			(at 345.44 87.63 0)
			(effects
				(font
					(size 1.27 1.27)
				)
				(hide yes)
			)
		)
		(property "Author" "Antmicro"
			(at 354.33 95.25 0)
			(effects
				(font
					(size 1.27 1.27)
					(thickness 0.15)
				)
				(justify left bottom)
				(hide yes)
			)
		)
		(property "License" "Apache-2.0"
			(at 354.33 97.79 0)
			(effects
				(font
					(size 1.27 1.27)
					(thickness 0.15)
				)
				(justify left bottom)
				(hide yes)
			)
		)
		(pin "1"
		)
		(instances
			(project "jetson-orin-baseboard"
				(path ""
					(reference "#PWR0274")
					(unit 1)
				)
			)
		)
	)
	(symbol
		(lib_id "antmicroTVSDiodes:TPD4E05U06QDQARQ1")
		(at 278.13 121.92 270)
		(mirror x)
		(unit 1)
		(exclude_from_sim no)
		(in_bom yes)
		(on_board yes)
		(dnp no)
		(property "Reference" "U21"
			(at 273.685 109.22 90)
			(effects
				(font
					(size 1.27 1.27)
				)
			)
		)
		(property "Value" "TPD4E05U06QDQARQ1"
			(at 267.97 97.79 0)
			(effects
				(font
					(size 1.27 1.27)
					(thickness 0.15)
				)
				(justify left bottom)
				(hide yes)
			)
		)
		(property "Footprint" "antmicro-footprints:USON-10_2.5x1mm_P0.5mm"
			(at 273.05 97.79 0)
			(effects
				(font
					(size 1.27 1.27)
					(thickness 0.15)
				)
				(justify left bottom)
				(hide yes)
			)
		)
		(property "Datasheet" "https://www.ti.com/lit/ds/symlink/tpd4e05u06-q1.pdf?HQS=dis-mous-null-mousermode-dsf-pf-null-wwe&ts=1663591265741&ref_url=https%253A%252F%252Fwww.mouser.com%252F"
			(at 270.51 97.79 0)
			(effects
				(font
					(size 1.27 1.27)
					(thickness 0.15)
				)
				(justify left bottom)
				(hide yes)
			)
		)
		(property "Description" ""
			(at 278.13 121.92 0)
			(effects
				(font
					(size 1.27 1.27)
				)
				(hide yes)
			)
		)
		(property "Manufacturer" "Texas Instruments"
			(at 265.43 97.79 0)
			(effects
				(font
					(size 1.27 1.27)
					(thickness 0.15)
				)
				(justify left bottom)
				(hide yes)
			)
		)
		(property "MPN" "TPD4E05U06QDQARQ1"
			(at 273.685 111.76 90)
			(effects
				(font
					(size 1.27 1.27)
					(thickness 0.15)
				)
			)
		)
		(property "Author" "Antmicro"
			(at 262.89 97.79 0)
			(effects
				(font
					(size 1.27 1.27)
					(thickness 0.15)
				)
				(justify left bottom)
				(hide yes)
			)
		)
		(property "License" "Apache-2.0"
			(at 260.35 97.79 0)
			(effects
				(font
					(size 1.27 1.27)
					(thickness 0.15)
				)
				(justify left bottom)
				(hide yes)
			)
		)
		(pin "1"
		)
		(pin "10"
		)
		(pin "2"
		)
		(pin "3"
		)
		(pin "4"
		)
		(pin "5"
		)
		(pin "6"
		)
		(pin "7"
		)
		(pin "8"
		)
		(pin "9"
		)
		(instances
			(project "jetson-orin-baseboard"
				(path ""
					(reference "U21")
					(unit 1)
				)
			)
		)
	)
	(symbol
		(lib_name "GND_3")
		(lib_id "antmicropower:GND")
		(at 129.54 109.22 0)
		(unit 1)
		(exclude_from_sim no)
		(in_bom yes)
		(on_board yes)
		(dnp no)
		(property "Reference" "#PWR0114"
			(at 129.54 115.57 0)
			(effects
				(font
					(size 1.27 1.27)
				)
				(justify left bottom)
				(hide yes)
			)
		)
		(property "Value" "GND"
			(at 129.54 113.03 0)
			(effects
				(font
					(size 1.27 1.27)
					(thickness 0.15)
				)
			)
		)
		(property "Footprint" ""
			(at 138.43 116.84 0)
			(effects
				(font
					(size 1.27 1.27)
					(thickness 0.15)
				)
				(justify left bottom)
				(hide yes)
			)
		)
		(property "Datasheet" ""
			(at 138.43 121.92 0)
			(effects
				(font
					(size 1.27 1.27)
					(thickness 0.15)
				)
				(justify left bottom)
				(hide yes)
			)
		)
		(property "Description" ""
			(at 129.54 109.22 0)
			(effects
				(font
					(size 1.27 1.27)
				)
				(hide yes)
			)
		)
		(property "Author" "Antmicro"
			(at 138.43 116.84 0)
			(effects
				(font
					(size 1.27 1.27)
					(thickness 0.15)
				)
				(justify left bottom)
				(hide yes)
			)
		)
		(property "License" "Apache-2.0"
			(at 138.43 119.38 0)
			(effects
				(font
					(size 1.27 1.27)
					(thickness 0.15)
				)
				(justify left bottom)
				(hide yes)
			)
		)
		(pin "1"
		)
		(instances
			(project "jetson-orin-baseboard"
				(path ""
					(reference "#PWR0114")
					(unit 1)
				)
			)
		)
	)
	(symbol
		(lib_name "GND_3")
		(lib_id "antmicropower:GND")
		(at 228.6 106.68 0)
		(unit 1)
		(exclude_from_sim no)
		(in_bom yes)
		(on_board yes)
		(dnp no)
		(property "Reference" "#PWR0123"
			(at 228.6 113.03 0)
			(effects
				(font
					(size 1.27 1.27)
				)
				(justify left bottom)
				(hide yes)
			)
		)
		(property "Value" "GND"
			(at 228.6 110.49 0)
			(effects
				(font
					(size 1.27 1.27)
					(thickness 0.15)
				)
			)
		)
		(property "Footprint" ""
			(at 237.49 114.3 0)
			(effects
				(font
					(size 1.27 1.27)
					(thickness 0.15)
				)
				(justify left bottom)
				(hide yes)
			)
		)
		(property "Datasheet" ""
			(at 237.49 119.38 0)
			(effects
				(font
					(size 1.27 1.27)
					(thickness 0.15)
				)
				(justify left bottom)
				(hide yes)
			)
		)
		(property "Description" ""
			(at 228.6 106.68 0)
			(effects
				(font
					(size 1.27 1.27)
				)
				(hide yes)
			)
		)
		(property "Author" "Antmicro"
			(at 237.49 114.3 0)
			(effects
				(font
					(size 1.27 1.27)
					(thickness 0.15)
				)
				(justify left bottom)
				(hide yes)
			)
		)
		(property "License" "Apache-2.0"
			(at 237.49 116.84 0)
			(effects
				(font
					(size 1.27 1.27)
					(thickness 0.15)
				)
				(justify left bottom)
				(hide yes)
			)
		)
		(pin "1"
		)
		(instances
			(project "jetson-orin-baseboard"
				(path ""
					(reference "#PWR0123")
					(unit 1)
				)
			)
		)
	)
	(symbol
		(lib_id "antmicroResistors0402:R_10k_0402")
		(at 335.28 87.63 180)
		(unit 1)
		(exclude_from_sim no)
		(in_bom no)
		(on_board yes)
		(dnp yes)
		(property "Reference" "R60"
			(at 335.28 86.995 0)
			(effects
				(font
					(size 1.27 1.27)
				)
				(justify right top)
			)
		)
		(property "Value" "R_10k_0402"
			(at 314.96 74.93 0)
			(effects
				(font
					(size 1.27 1.27)
					(thickness 0.15)
				)
				(justify left bottom)
				(hide yes)
			)
		)
		(property "Footprint" "antmicro-footprints:R_0402_1005Metric"
			(at 314.96 72.39 0)
			(effects
				(font
					(size 1.27 1.27)
					(thickness 0.15)
				)
				(justify left bottom)
				(hide yes)
			)
		)
		(property "Datasheet" "https://www.bourns.com/docs/product-datasheets/cr.pdf"
			(at 314.96 69.85 0)
			(effects
				(font
					(size 1.27 1.27)
					(thickness 0.15)
				)
				(justify left bottom)
				(hide yes)
			)
		)
		(property "Description" ""
			(at 335.28 87.63 0)
			(effects
				(font
					(size 1.27 1.27)
				)
				(hide yes)
			)
		)
		(property "Manufacturer" "Bourns"
			(at 314.96 64.77 0)
			(effects
				(font
					(size 1.27 1.27)
					(thickness 0.15)
				)
				(justify left bottom)
				(hide yes)
			)
		)
		(property "MPN" "CR0402-FX-1002GLF"
			(at 314.96 67.31 0)
			(effects
				(font
					(size 1.27 1.27)
					(thickness 0.15)
				)
				(justify left bottom)
				(hide yes)
			)
		)
		(property "Val" "10k"
			(at 326.39 86.995 0)
			(effects
				(font
					(size 1.27 1.27)
					(thickness 0.15)
				)
				(justify right top)
			)
		)
		(property "License" "Apache-2.0"
			(at 314.96 62.23 0)
			(effects
				(font
					(size 1.27 1.27)
					(thickness 0.15)
				)
				(justify left bottom)
				(hide yes)
			)
		)
		(property "Author" "Antmicro"
			(at 314.96 59.69 0)
			(effects
				(font
					(size 1.27 1.27)
					(thickness 0.15)
				)
				(justify left bottom)
				(hide yes)
			)
		)
		(property "Tolerance" "1%"
			(at 314.96 77.47 0)
			(effects
				(font
					(size 1.27 1.27)
				)
				(justify left bottom)
				(hide yes)
			)
		)
		(pin "1"
		)
		(pin "2"
		)
		(instances
			(project "jetson-orin-baseboard"
				(path ""
					(reference "R60")
					(unit 1)
				)
			)
		)
	)
	(symbol
		(lib_name "R_0R_0402_9")
		(lib_id "antmicroResistors0402:R_0R_0402")
		(at 120.65 139.7 0)
		(unit 1)
		(exclude_from_sim no)
		(in_bom yes)
		(on_board yes)
		(dnp no)
		(property "Reference" "R118"
			(at 125.73 139.065 0)
			(effects
				(font
					(size 1.27 1.27)
				)
				(justify left bottom)
			)
		)
		(property "Value" "R_0R_0402"
			(at 140.97 152.4 0)
			(effects
				(font
					(size 1.27 1.27)
					(thickness 0.15)
				)
				(justify left bottom)
				(hide yes)
			)
		)
		(property "Footprint" "antmicro-footprints:R_0402_1005Metric"
			(at 140.97 154.94 0)
			(effects
				(font
					(size 1.27 1.27)
					(thickness 0.15)
				)
				(justify left bottom)
				(hide yes)
			)
		)
		(property "Datasheet" "https://industrial.panasonic.com/cdbs/www-data/pdf/RDA0000/AOA0000C301.pdf"
			(at 140.97 157.48 0)
			(effects
				(font
					(size 1.27 1.27)
					(thickness 0.15)
				)
				(justify left bottom)
				(hide yes)
			)
		)
		(property "Description" ""
			(at 120.65 139.7 0)
			(effects
				(font
					(size 1.27 1.27)
				)
				(hide yes)
			)
		)
		(property "Manufacturer" "Panasonic"
			(at 140.97 162.56 0)
			(effects
				(font
					(size 1.27 1.27)
					(thickness 0.15)
				)
				(justify left bottom)
				(hide yes)
			)
		)
		(property "MPN" "ERJ2GE0R00X"
			(at 140.97 160.02 0)
			(effects
				(font
					(size 1.27 1.27)
					(thickness 0.15)
				)
				(justify left bottom)
				(hide yes)
			)
		)
		(property "Val" "0R"
			(at 118.11 139.065 0)
			(effects
				(font
					(size 1.27 1.27)
					(thickness 0.15)
				)
				(justify left bottom)
			)
		)
		(property "License" "Apache-2.0"
			(at 140.97 165.1 0)
			(effects
				(font
					(size 1.27 1.27)
					(thickness 0.15)
				)
				(justify left bottom)
				(hide yes)
			)
		)
		(property "Author" "Antmicro"
			(at 140.97 167.64 0)
			(effects
				(font
					(size 1.27 1.27)
					(thickness 0.15)
				)
				(justify left bottom)
				(hide yes)
			)
		)
		(property "Tolerance" "~"
			(at 140.97 149.86 0)
			(effects
				(font
					(size 1.27 1.27)
				)
				(justify left bottom)
				(hide yes)
			)
		)
		(property "Current" "1A"
			(at 140.97 170.18 0)
			(effects
				(font
					(size 1.27 1.27)
					(thickness 0.15)
				)
				(justify left bottom)
				(hide yes)
			)
		)
		(pin "1"
		)
		(pin "2"
		)
		(instances
			(project "jetson-orin-baseboard"
				(path ""
					(reference "R118")
					(unit 1)
				)
			)
		)
	)
	(symbol
		(lib_name "GND_3")
		(lib_id "antmicropower:GND")
		(at 355.6 87.63 0)
		(unit 1)
		(exclude_from_sim no)
		(in_bom yes)
		(on_board yes)
		(dnp no)
		(property "Reference" "#PWR0277"
			(at 355.6 93.98 0)
			(effects
				(font
					(size 1.27 1.27)
				)
				(justify left bottom)
				(hide yes)
			)
		)
		(property "Value" "GND"
			(at 355.6 91.44 0)
			(effects
				(font
					(size 1.27 1.27)
					(thickness 0.15)
				)
			)
		)
		(property "Footprint" ""
			(at 364.49 95.25 0)
			(effects
				(font
					(size 1.27 1.27)
					(thickness 0.15)
				)
				(justify left bottom)
				(hide yes)
			)
		)
		(property "Datasheet" ""
			(at 364.49 100.33 0)
			(effects
				(font
					(size 1.27 1.27)
					(thickness 0.15)
				)
				(justify left bottom)
				(hide yes)
			)
		)
		(property "Description" ""
			(at 355.6 87.63 0)
			(effects
				(font
					(size 1.27 1.27)
				)
				(hide yes)
			)
		)
		(property "Author" "Antmicro"
			(at 364.49 95.25 0)
			(effects
				(font
					(size 1.27 1.27)
					(thickness 0.15)
				)
				(justify left bottom)
				(hide yes)
			)
		)
		(property "License" "Apache-2.0"
			(at 364.49 97.79 0)
			(effects
				(font
					(size 1.27 1.27)
					(thickness 0.15)
				)
				(justify left bottom)
				(hide yes)
			)
		)
		(pin "1"
		)
		(instances
			(project "jetson-orin-baseboard"
				(path ""
					(reference "#PWR0277")
					(unit 1)
				)
			)
		)
	)
	(symbol
		(lib_name "GND_3")
		(lib_id "antmicropower:GND")
		(at 288.29 196.85 0)
		(unit 1)
		(exclude_from_sim no)
		(in_bom yes)
		(on_board yes)
		(dnp no)
		(property "Reference" "#PWR0131"
			(at 288.29 203.2 0)
			(effects
				(font
					(size 1.27 1.27)
				)
				(justify left bottom)
				(hide yes)
			)
		)
		(property "Value" "GND"
			(at 288.29 200.66 0)
			(effects
				(font
					(size 1.27 1.27)
					(thickness 0.15)
				)
			)
		)
		(property "Footprint" ""
			(at 297.18 204.47 0)
			(effects
				(font
					(size 1.27 1.27)
					(thickness 0.15)
				)
				(justify left bottom)
				(hide yes)
			)
		)
		(property "Datasheet" ""
			(at 297.18 209.55 0)
			(effects
				(font
					(size 1.27 1.27)
					(thickness 0.15)
				)
				(justify left bottom)
				(hide yes)
			)
		)
		(property "Description" ""
			(at 288.29 196.85 0)
			(effects
				(font
					(size 1.27 1.27)
				)
				(hide yes)
			)
		)
		(property "Author" "Antmicro"
			(at 297.18 204.47 0)
			(effects
				(font
					(size 1.27 1.27)
					(thickness 0.15)
				)
				(justify left bottom)
				(hide yes)
			)
		)
		(property "License" "Apache-2.0"
			(at 297.18 207.01 0)
			(effects
				(font
					(size 1.27 1.27)
					(thickness 0.15)
				)
				(justify left bottom)
				(hide yes)
			)
		)
		(pin "1"
		)
		(instances
			(project "jetson-orin-baseboard"
				(path ""
					(reference "#PWR0131")
					(unit 1)
				)
			)
		)
	)
	(symbol
		(lib_name "C_100n_0402_2")
		(lib_id "antmicroCapacitors0402:C_100n_0402")
		(at 129.54 102.87 90)
		(mirror x)
		(unit 1)
		(exclude_from_sim no)
		(in_bom yes)
		(on_board yes)
		(dnp no)
		(fields_autoplaced yes)
		(property "Reference" "C68"
			(at 132.08 104.1463 90)
			(effects
				(font
					(size 1.27 1.27)
				)
				(justify right)
			)
		)
		(property "Value" "C_100n_0402"
			(at 139.7 123.19 0)
			(effects
				(font
					(size 1.27 1.27)
					(thickness 0.15)
				)
				(justify left bottom)
				(hide yes)
			)
		)
		(property "Footprint" "antmicro-footprints:C_0402_1005Metric"
			(at 142.24 123.19 0)
			(effects
				(font
					(size 1.27 1.27)
					(thickness 0.15)
				)
				(justify left bottom)
				(hide yes)
			)
		)
		(property "Datasheet" "https://www.murata.com/products/productdetail?partno=GRM155R61H104KE14%23"
			(at 144.78 123.19 0)
			(effects
				(font
					(size 1.27 1.27)
					(thickness 0.15)
				)
				(justify left bottom)
				(hide yes)
			)
		)
		(property "Description" ""
			(at 129.54 102.87 0)
			(effects
				(font
					(size 1.27 1.27)
				)
				(hide yes)
			)
		)
		(property "Manufacturer" "Murata"
			(at 149.86 123.19 0)
			(effects
				(font
					(size 1.27 1.27)
					(thickness 0.15)
				)
				(justify left bottom)
				(hide yes)
			)
		)
		(property "MPN" "GRM155R61H104KE14D"
			(at 147.32 123.19 0)
			(effects
				(font
					(size 1.27 1.27)
					(thickness 0.15)
				)
				(justify left bottom)
				(hide yes)
			)
		)
		(property "Val" "100n"
			(at 132.08 106.6863 90)
			(effects
				(font
					(size 1.27 1.27)
					(thickness 0.15)
				)
				(justify right)
			)
		)
		(property "License" "Apache-2.0"
			(at 152.4 123.19 0)
			(effects
				(font
					(size 1.27 1.27)
					(thickness 0.15)
				)
				(justify left bottom)
				(hide yes)
			)
		)
		(property "Author" "Antmicro"
			(at 154.94 123.19 0)
			(effects
				(font
					(size 1.27 1.27)
					(thickness 0.15)
				)
				(justify left bottom)
				(hide yes)
			)
		)
		(property "Voltage" "50V"
			(at 157.48 123.19 0)
			(effects
				(font
					(size 1.27 1.27)
				)
				(justify left bottom)
				(hide yes)
			)
		)
		(property "Dielectric" "X5R"
			(at 160.02 123.19 0)
			(effects
				(font
					(size 1.27 1.27)
				)
				(justify left bottom)
				(hide yes)
			)
		)
		(pin "1"
		)
		(pin "2"
		)
		(instances
			(project "jetson-orin-baseboard"
				(path ""
					(reference "C68")
					(unit 1)
				)
			)
		)
	)
	(symbol
		(lib_name "R_0R_0402_10")
		(lib_id "antmicroResistors0402:R_0R_0402")
		(at 119.38 157.48 0)
		(unit 1)
		(exclude_from_sim no)
		(in_bom yes)
		(on_board yes)
		(dnp no)
		(property "Reference" "R201"
			(at 124.46 156.845 0)
			(effects
				(font
					(size 1.27 1.27)
				)
				(justify left bottom)
			)
		)
		(property "Value" "R_0R_0402"
			(at 139.7 170.18 0)
			(effects
				(font
					(size 1.27 1.27)
					(thickness 0.15)
				)
				(justify left bottom)
				(hide yes)
			)
		)
		(property "Footprint" "antmicro-footprints:R_0402_1005Metric"
			(at 139.7 172.72 0)
			(effects
				(font
					(size 1.27 1.27)
					(thickness 0.15)
				)
				(justify left bottom)
				(hide yes)
			)
		)
		(property "Datasheet" "https://industrial.panasonic.com/cdbs/www-data/pdf/RDA0000/AOA0000C301.pdf"
			(at 139.7 175.26 0)
			(effects
				(font
					(size 1.27 1.27)
					(thickness 0.15)
				)
				(justify left bottom)
				(hide yes)
			)
		)
		(property "Description" ""
			(at 119.38 157.48 0)
			(effects
				(font
					(size 1.27 1.27)
				)
				(hide yes)
			)
		)
		(property "Manufacturer" "Panasonic"
			(at 139.7 180.34 0)
			(effects
				(font
					(size 1.27 1.27)
					(thickness 0.15)
				)
				(justify left bottom)
				(hide yes)
			)
		)
		(property "MPN" "ERJ2GE0R00X"
			(at 139.7 177.8 0)
			(effects
				(font
					(size 1.27 1.27)
					(thickness 0.15)
				)
				(justify left bottom)
				(hide yes)
			)
		)
		(property "Val" "0R"
			(at 116.84 156.845 0)
			(effects
				(font
					(size 1.27 1.27)
					(thickness 0.15)
				)
				(justify left bottom)
			)
		)
		(property "License" "Apache-2.0"
			(at 139.7 182.88 0)
			(effects
				(font
					(size 1.27 1.27)
					(thickness 0.15)
				)
				(justify left bottom)
				(hide yes)
			)
		)
		(property "Author" "Antmicro"
			(at 139.7 185.42 0)
			(effects
				(font
					(size 1.27 1.27)
					(thickness 0.15)
				)
				(justify left bottom)
				(hide yes)
			)
		)
		(property "Tolerance" "~"
			(at 139.7 167.64 0)
			(effects
				(font
					(size 1.27 1.27)
				)
				(justify left bottom)
				(hide yes)
			)
		)
		(property "Current" "1A"
			(at 139.7 187.96 0)
			(effects
				(font
					(size 1.27 1.27)
					(thickness 0.15)
				)
				(justify left bottom)
				(hide yes)
			)
		)
		(pin "1"
		)
		(pin "2"
		)
		(instances
			(project "jetson-orin-baseboard"
				(path ""
					(reference "R201")
					(unit 1)
				)
			)
		)
	)
	(symbol
		(lib_name "C_10u_0603_1")
		(lib_id "antmicroCapacitors0603:C_10u_0603")
		(at 142.24 102.87 90)
		(mirror x)
		(unit 1)
		(exclude_from_sim no)
		(in_bom yes)
		(on_board yes)
		(dnp no)
		(fields_autoplaced yes)
		(property "Reference" "C66"
			(at 144.78 104.1463 90)
			(effects
				(font
					(size 1.27 1.27)
				)
				(justify right)
			)
		)
		(property "Value" "C_10u_0603"
			(at 152.4 123.19 0)
			(effects
				(font
					(size 1.27 1.27)
					(thickness 0.15)
				)
				(justify left bottom)
				(hide yes)
			)
		)
		(property "Footprint" "antmicro-footprints:C_0603_1608Metric"
			(at 154.94 123.19 0)
			(effects
				(font
					(size 1.27 1.27)
					(thickness 0.15)
				)
				(justify left bottom)
				(hide yes)
			)
		)
		(property "Datasheet" "https://www.murata.com/products/productdetail?partno=GRM188R61A106KE69%23"
			(at 157.48 123.19 0)
			(effects
				(font
					(size 1.27 1.27)
					(thickness 0.15)
				)
				(justify left bottom)
				(hide yes)
			)
		)
		(property "Description" ""
			(at 142.24 102.87 0)
			(effects
				(font
					(size 1.27 1.27)
				)
				(hide yes)
			)
		)
		(property "Manufacturer" "Murata"
			(at 162.56 123.19 0)
			(effects
				(font
					(size 1.27 1.27)
					(thickness 0.15)
				)
				(justify left bottom)
				(hide yes)
			)
		)
		(property "MPN" "GRM188R61A106KE69D"
			(at 160.02 123.19 0)
			(effects
				(font
					(size 1.27 1.27)
					(thickness 0.15)
				)
				(justify left bottom)
				(hide yes)
			)
		)
		(property "Val" "10u"
			(at 144.78 106.6863 90)
			(effects
				(font
					(size 1.27 1.27)
					(thickness 0.15)
				)
				(justify right)
			)
		)
		(property "License" "Apache-2.0"
			(at 165.1 123.19 0)
			(effects
				(font
					(size 1.27 1.27)
					(thickness 0.15)
				)
				(justify left bottom)
				(hide yes)
			)
		)
		(property "Author" "Antmicro"
			(at 167.64 123.19 0)
			(effects
				(font
					(size 1.27 1.27)
					(thickness 0.15)
				)
				(justify left bottom)
				(hide yes)
			)
		)
		(property "Voltage" ""
			(at 170.18 123.19 0)
			(effects
				(font
					(size 1.27 1.27)
				)
				(justify left bottom)
				(hide yes)
			)
		)
		(property "Dielectric" "template_dielectric"
			(at 172.72 123.19 0)
			(effects
				(font
					(size 1.27 1.27)
				)
				(justify left bottom)
				(hide yes)
			)
		)
		(pin "1"
		)
		(pin "2"
		)
		(instances
			(project "jetson-orin-baseboard"
				(path ""
					(reference "C66")
					(unit 1)
				)
			)
		)
	)
	(symbol
		(lib_name "GND_3")
		(lib_id "antmicropower:GND")
		(at 267.97 123.19 0)
		(unit 1)
		(exclude_from_sim no)
		(in_bom yes)
		(on_board yes)
		(dnp no)
		(property "Reference" "#PWR0127"
			(at 267.97 129.54 0)
			(effects
				(font
					(size 1.27 1.27)
				)
				(justify left bottom)
				(hide yes)
			)
		)
		(property "Value" "GND"
			(at 267.97 127 0)
			(effects
				(font
					(size 1.27 1.27)
					(thickness 0.15)
				)
			)
		)
		(property "Footprint" ""
			(at 276.86 130.81 0)
			(effects
				(font
					(size 1.27 1.27)
					(thickness 0.15)
				)
				(justify left bottom)
				(hide yes)
			)
		)
		(property "Datasheet" ""
			(at 276.86 135.89 0)
			(effects
				(font
					(size 1.27 1.27)
					(thickness 0.15)
				)
				(justify left bottom)
				(hide yes)
			)
		)
		(property "Description" ""
			(at 267.97 123.19 0)
			(effects
				(font
					(size 1.27 1.27)
				)
				(hide yes)
			)
		)
		(property "Author" "Antmicro"
			(at 276.86 130.81 0)
			(effects
				(font
					(size 1.27 1.27)
					(thickness 0.15)
				)
				(justify left bottom)
				(hide yes)
			)
		)
		(property "License" "Apache-2.0"
			(at 276.86 133.35 0)
			(effects
				(font
					(size 1.27 1.27)
					(thickness 0.15)
				)
				(justify left bottom)
				(hide yes)
			)
		)
		(pin "1"
		)
		(instances
			(project "jetson-orin-baseboard"
				(path ""
					(reference "#PWR0127")
					(unit 1)
				)
			)
		)
	)
	(symbol
		(lib_id "antmicroResistors0402:R_10k_0402")
		(at 219.71 92.71 180)
		(unit 1)
		(exclude_from_sim no)
		(in_bom yes)
		(on_board yes)
		(dnp no)
		(property "Reference" "R137"
			(at 224.79 90.805 0)
			(effects
				(font
					(size 1.27 1.27)
				)
				(justify left bottom)
			)
		)
		(property "Value" "R_10k_0402"
			(at 199.39 80.01 0)
			(effects
				(font
					(size 1.27 1.27)
					(thickness 0.15)
				)
				(justify left bottom)
				(hide yes)
			)
		)
		(property "Footprint" "antmicro-footprints:R_0402_1005Metric"
			(at 199.39 77.47 0)
			(effects
				(font
					(size 1.27 1.27)
					(thickness 0.15)
				)
				(justify left bottom)
				(hide yes)
			)
		)
		(property "Datasheet" "https://www.bourns.com/docs/product-datasheets/cr.pdf"
			(at 199.39 74.93 0)
			(effects
				(font
					(size 1.27 1.27)
					(thickness 0.15)
				)
				(justify left bottom)
				(hide yes)
			)
		)
		(property "Description" ""
			(at 219.71 92.71 0)
			(effects
				(font
					(size 1.27 1.27)
				)
				(hide yes)
			)
		)
		(property "Manufacturer" "Bourns"
			(at 199.39 69.85 0)
			(effects
				(font
					(size 1.27 1.27)
					(thickness 0.15)
				)
				(justify left bottom)
				(hide yes)
			)
		)
		(property "MPN" "CR0402-FX-1002GLF"
			(at 199.39 72.39 0)
			(effects
				(font
					(size 1.27 1.27)
					(thickness 0.15)
				)
				(justify left bottom)
				(hide yes)
			)
		)
		(property "Val" "10k"
			(at 214.63 90.805 0)
			(effects
				(font
					(size 1.27 1.27)
					(thickness 0.15)
				)
				(justify left bottom)
			)
		)
		(property "License" "Apache-2.0"
			(at 199.39 67.31 0)
			(effects
				(font
					(size 1.27 1.27)
					(thickness 0.15)
				)
				(justify left bottom)
				(hide yes)
			)
		)
		(property "Author" "Antmicro"
			(at 199.39 64.77 0)
			(effects
				(font
					(size 1.27 1.27)
					(thickness 0.15)
				)
				(justify left bottom)
				(hide yes)
			)
		)
		(property "Tolerance" "1%"
			(at 199.39 82.55 0)
			(effects
				(font
					(size 1.27 1.27)
				)
				(justify left bottom)
				(hide yes)
			)
		)
		(pin "1"
		)
		(pin "2"
		)
		(instances
			(project "jetson-orin-baseboard"
				(path ""
					(reference "R137")
					(unit 1)
				)
			)
		)
	)
	(symbol
		(lib_id "antmicroTVSDiodes:ESD9X5.0ST5G")
		(at 290.83 88.9 270)
		(unit 1)
		(exclude_from_sim no)
		(in_bom yes)
		(on_board yes)
		(dnp no)
		(property "Reference" "D10"
			(at 292.1 90.17 90)
			(effects
				(font
					(size 1.27 1.27)
				)
				(justify left)
			)
		)
		(property "Value" "ESD9X5.0ST5G"
			(at 275.59 110.49 0)
			(effects
				(font
					(size 1.27 1.27)
					(thickness 0.15)
				)
				(justify left bottom)
				(hide yes)
			)
		)
		(property "Footprint" "antmicro-footprints:SOD-923"
			(at 283.21 110.49 0)
			(effects
				(font
					(size 1.27 1.27)
					(thickness 0.15)
				)
				(justify left bottom)
				(hide yes)
			)
		)
		(property "Datasheet" "https://www.onsemi.com/pdf/datasheet/esd9x3.3st5g-d.pdf"
			(at 280.67 110.49 0)
			(effects
				(font
					(size 1.27 1.27)
					(thickness 0.15)
				)
				(justify left bottom)
				(hide yes)
			)
		)
		(property "Description" ""
			(at 290.83 88.9 0)
			(effects
				(font
					(size 1.27 1.27)
				)
				(hide yes)
			)
		)
		(property "Manufacturer" "ON Semiconductor"
			(at 278.13 110.49 0)
			(effects
				(font
					(size 1.27 1.27)
					(thickness 0.15)
				)
				(justify left bottom)
				(hide yes)
			)
		)
		(property "MPN" "ESD9X5.0ST5G"
			(at 292.1 92.71 90)
			(effects
				(font
					(size 1.27 1.27)
					(thickness 0.15)
				)
				(justify left)
			)
		)
		(property "Author" "Antmicro"
			(at 273.05 110.49 0)
			(effects
				(font
					(size 1.27 1.27)
					(thickness 0.15)
				)
				(justify left bottom)
				(hide yes)
			)
		)
		(property "License" "Apache-2.0"
			(at 270.51 110.49 0)
			(effects
				(font
					(size 1.27 1.27)
					(thickness 0.15)
				)
				(justify left bottom)
				(hide yes)
			)
		)
		(pin "1"
		)
		(pin "2"
		)
		(instances
			(project "jetson-orin-baseboard"
				(path ""
					(reference "D10")
					(unit 1)
				)
			)
		)
	)
	(symbol
		(lib_id "antmicropower:+5V")
		(at 226.06 73.66 0)
		(unit 1)
		(exclude_from_sim no)
		(in_bom yes)
		(on_board yes)
		(dnp no)
		(property "Reference" "#PWR0121"
			(at 226.06 77.47 0)
			(effects
				(font
					(size 1.27 1.27)
				)
				(justify left bottom)
				(hide yes)
			)
		)
		(property "Value" "+5V"
			(at 224.155 70.485 0)
			(effects
				(font
					(size 1.27 1.27)
					(thickness 0.15)
				)
				(justify left bottom)
			)
		)
		(property "Footprint" ""
			(at 241.3 81.28 0)
			(effects
				(font
					(size 1.27 1.27)
					(thickness 0.15)
				)
				(justify left bottom)
				(hide yes)
			)
		)
		(property "Datasheet" ""
			(at 241.3 83.82 0)
			(effects
				(font
					(size 1.27 1.27)
					(thickness 0.15)
				)
				(justify left bottom)
				(hide yes)
			)
		)
		(property "Description" ""
			(at 226.06 73.66 0)
			(effects
				(font
					(size 1.27 1.27)
				)
				(hide yes)
			)
		)
		(property "Author" "Antmicro"
			(at 241.3 81.28 0)
			(effects
				(font
					(size 1.27 1.27)
					(thickness 0.15)
				)
				(justify left bottom)
				(hide yes)
			)
		)
		(property "License" "Apache-2.0"
			(at 241.3 83.82 0)
			(effects
				(font
					(size 1.27 1.27)
					(thickness 0.15)
				)
				(justify left bottom)
				(hide yes)
			)
		)
		(pin "1"
		)
		(instances
			(project "jetson-orin-baseboard"
				(path ""
					(reference "#PWR0121")
					(unit 1)
				)
			)
		)
	)
	(symbol
		(lib_id "antmicroCapacitors0402:C_100n_0402")
		(at 207.01 177.8 180)
		(unit 1)
		(exclude_from_sim no)
		(in_bom yes)
		(on_board yes)
		(dnp no)
		(property "Reference" "C69"
			(at 209.55 175.895 0)
			(effects
				(font
					(size 1.27 1.27)
				)
				(justify left bottom)
			)
		)
		(property "Value" "C_100n_0402"
			(at 186.69 167.64 0)
			(effects
				(font
					(size 1.27 1.27)
					(thickness 0.15)
				)
				(justify left bottom)
				(hide yes)
			)
		)
		(property "Footprint" "antmicro-footprints:C_0402_1005Metric"
			(at 186.69 165.1 0)
			(effects
				(font
					(size 1.27 1.27)
					(thickness 0.15)
				)
				(justify left bottom)
				(hide yes)
			)
		)
		(property "Datasheet" "https://www.murata.com/products/productdetail?partno=GRM155R61H104KE14%23"
			(at 186.69 162.56 0)
			(effects
				(font
					(size 1.27 1.27)
					(thickness 0.15)
				)
				(justify left bottom)
				(hide yes)
			)
		)
		(property "Description" ""
			(at 207.01 177.8 0)
			(effects
				(font
					(size 1.27 1.27)
				)
				(hide yes)
			)
		)
		(property "Manufacturer" "Murata"
			(at 186.69 157.48 0)
			(effects
				(font
					(size 1.27 1.27)
					(thickness 0.15)
				)
				(justify left bottom)
				(hide yes)
			)
		)
		(property "MPN" "GRM155R61H104KE14D"
			(at 186.69 160.02 0)
			(effects
				(font
					(size 1.27 1.27)
					(thickness 0.15)
				)
				(justify left bottom)
				(hide yes)
			)
		)
		(property "Val" "100n"
			(at 203.2 178.435 0)
			(effects
				(font
					(size 1.27 1.27)
					(thickness 0.15)
				)
				(justify left bottom)
			)
		)
		(property "License" "Apache-2.0"
			(at 186.69 154.94 0)
			(effects
				(font
					(size 1.27 1.27)
					(thickness 0.15)
				)
				(justify left bottom)
				(hide yes)
			)
		)
		(property "Author" "Antmicro"
			(at 186.69 152.4 0)
			(effects
				(font
					(size 1.27 1.27)
					(thickness 0.15)
				)
				(justify left bottom)
				(hide yes)
			)
		)
		(property "Voltage" "50V"
			(at 186.69 149.86 0)
			(effects
				(font
					(size 1.27 1.27)
				)
				(justify left bottom)
				(hide yes)
			)
		)
		(property "Dielectric" "X5R"
			(at 186.69 147.32 0)
			(effects
				(font
					(size 1.27 1.27)
				)
				(justify left bottom)
				(hide yes)
			)
		)
		(pin "1"
		)
		(pin "2"
		)
		(instances
			(project "jetson-orin-baseboard"
				(path ""
					(reference "C69")
					(unit 1)
				)
			)
		)
	)
	(symbol
		(lib_id "antmicroResistors0402:R_10k_0402")
		(at 199.39 114.3 90)
		(unit 1)
		(exclude_from_sim no)
		(in_bom yes)
		(on_board yes)
		(dnp no)
		(property "Reference" "R135"
			(at 200.66 110.49 90)
			(effects
				(font
					(size 1.27 1.27)
				)
				(justify right)
			)
		)
		(property "Value" "R_10k_0402"
			(at 212.09 93.98 0)
			(effects
				(font
					(size 1.27 1.27)
					(thickness 0.15)
				)
				(justify left bottom)
				(hide yes)
			)
		)
		(property "Footprint" "antmicro-footprints:R_0402_1005Metric"
			(at 214.63 93.98 0)
			(effects
				(font
					(size 1.27 1.27)
					(thickness 0.15)
				)
				(justify left bottom)
				(hide yes)
			)
		)
		(property "Datasheet" "https://www.bourns.com/docs/product-datasheets/cr.pdf"
			(at 217.17 93.98 0)
			(effects
				(font
					(size 1.27 1.27)
					(thickness 0.15)
				)
				(justify left bottom)
				(hide yes)
			)
		)
		(property "Description" ""
			(at 199.39 114.3 0)
			(effects
				(font
					(size 1.27 1.27)
				)
				(hide yes)
			)
		)
		(property "Manufacturer" "Bourns"
			(at 222.25 93.98 0)
			(effects
				(font
					(size 1.27 1.27)
					(thickness 0.15)
				)
				(justify left bottom)
				(hide yes)
			)
		)
		(property "MPN" "CR0402-FX-1002GLF"
			(at 219.71 93.98 0)
			(effects
				(font
					(size 1.27 1.27)
					(thickness 0.15)
				)
				(justify left bottom)
				(hide yes)
			)
		)
		(property "Val" "10k"
			(at 200.66 113.03 90)
			(effects
				(font
					(size 1.27 1.27)
					(thickness 0.15)
				)
				(justify right)
			)
		)
		(property "License" "Apache-2.0"
			(at 224.79 93.98 0)
			(effects
				(font
					(size 1.27 1.27)
					(thickness 0.15)
				)
				(justify left bottom)
				(hide yes)
			)
		)
		(property "Author" "Antmicro"
			(at 227.33 93.98 0)
			(effects
				(font
					(size 1.27 1.27)
					(thickness 0.15)
				)
				(justify left bottom)
				(hide yes)
			)
		)
		(property "Tolerance" "1%"
			(at 209.55 93.98 0)
			(effects
				(font
					(size 1.27 1.27)
				)
				(justify left bottom)
				(hide yes)
			)
		)
		(pin "1"
		)
		(pin "2"
		)
		(instances
			(project "jetson-orin-baseboard"
				(path ""
					(reference "R135")
					(unit 1)
				)
			)
		)
	)
	(symbol
		(lib_id "antmicropower:+3V3")
		(at 204.47 76.2 0)
		(unit 1)
		(exclude_from_sim no)
		(in_bom yes)
		(on_board yes)
		(dnp no)
		(property "Reference" "#PWR0289"
			(at 204.47 80.01 0)
			(effects
				(font
					(size 1.27 1.27)
				)
				(justify left bottom)
				(hide yes)
			)
		)
		(property "Value" "+3V3"
			(at 201.295 72.39 0)
			(effects
				(font
					(size 1.27 1.27)
					(thickness 0.15)
				)
				(justify left)
			)
		)
		(property "Footprint" ""
			(at 219.71 83.82 0)
			(effects
				(font
					(size 1.27 1.27)
					(thickness 0.15)
				)
				(justify left bottom)
				(hide yes)
			)
		)
		(property "Datasheet" ""
			(at 219.71 86.36 0)
			(effects
				(font
					(size 1.27 1.27)
					(thickness 0.15)
				)
				(justify left bottom)
				(hide yes)
			)
		)
		(property "Description" ""
			(at 204.47 76.2 0)
			(effects
				(font
					(size 1.27 1.27)
				)
				(hide yes)
			)
		)
		(property "Author" "Antmicro"
			(at 219.71 78.74 0)
			(effects
				(font
					(size 1.27 1.27)
					(thickness 0.15)
				)
				(justify left bottom)
				(hide yes)
			)
		)
		(property "License" "Apache-2.0"
			(at 219.71 81.28 0)
			(effects
				(font
					(size 1.27 1.27)
					(thickness 0.15)
				)
				(justify left bottom)
				(hide yes)
			)
		)
		(pin "1"
		)
		(instances
			(project "jetson-orin-baseboard"
				(path ""
					(reference "#PWR0289")
					(unit 1)
				)
			)
		)
	)
	(symbol
		(lib_id "antmicroResistors0402:R_2k2_0402")
		(at 254 96.52 90)
		(unit 1)
		(exclude_from_sim no)
		(in_bom yes)
		(on_board yes)
		(dnp no)
		(property "Reference" "R139"
			(at 255.27 92.71 90)
			(effects
				(font
					(size 1.27 1.27)
				)
				(justify right)
			)
		)
		(property "Value" "R_2k2_0402"
			(at 266.7 76.2 0)
			(effects
				(font
					(size 1.27 1.27)
					(thickness 0.15)
				)
				(justify left bottom)
				(hide yes)
			)
		)
		(property "Footprint" "antmicro-footprints:R_0402_1005Metric"
			(at 269.24 76.2 0)
			(effects
				(font
					(size 1.27 1.27)
					(thickness 0.15)
				)
				(justify left bottom)
				(hide yes)
			)
		)
		(property "Datasheet" "https://www.bourns.com/docs/product-datasheets/cr.pdf"
			(at 271.78 76.2 0)
			(effects
				(font
					(size 1.27 1.27)
					(thickness 0.15)
				)
				(justify left bottom)
				(hide yes)
			)
		)
		(property "Description" ""
			(at 254 96.52 0)
			(effects
				(font
					(size 1.27 1.27)
				)
				(hide yes)
			)
		)
		(property "Manufacturer" "Bourns"
			(at 276.86 76.2 0)
			(effects
				(font
					(size 1.27 1.27)
					(thickness 0.15)
				)
				(justify left bottom)
				(hide yes)
			)
		)
		(property "MPN" "CR0402-FX-2201GLF"
			(at 274.32 76.2 0)
			(effects
				(font
					(size 1.27 1.27)
					(thickness 0.15)
				)
				(justify left bottom)
				(hide yes)
			)
		)
		(property "Val" "2k2"
			(at 255.27 95.25 90)
			(effects
				(font
					(size 1.27 1.27)
					(thickness 0.15)
				)
				(justify right)
			)
		)
		(property "License" "Apache-2.0"
			(at 279.4 76.2 0)
			(effects
				(font
					(size 1.27 1.27)
					(thickness 0.15)
				)
				(justify left bottom)
				(hide yes)
			)
		)
		(property "Author" "Antmicro"
			(at 281.94 76.2 0)
			(effects
				(font
					(size 1.27 1.27)
					(thickness 0.15)
				)
				(justify left bottom)
				(hide yes)
			)
		)
		(property "Tolerance" "1%"
			(at 264.16 76.2 0)
			(effects
				(font
					(size 1.27 1.27)
				)
				(justify left bottom)
				(hide yes)
			)
		)
		(pin "1"
		)
		(pin "2"
		)
		(instances
			(project "jetson-orin-baseboard"
				(path ""
					(reference "R139")
					(unit 1)
				)
			)
		)
	)
	(symbol
		(lib_id "antmicroTransistorsFETsMOSFETsSingle:PJE138K")
		(at 222.25 102.87 0)
		(unit 1)
		(exclude_from_sim no)
		(in_bom yes)
		(on_board yes)
		(dnp no)
		(property "Reference" "Q4"
			(at 231.14 99.06 0)
			(effects
				(font
					(size 1.27 1.27)
					(thickness 0.15)
				)
				(justify left)
			)
		)
		(property "Value" "PJE138K"
			(at 245.11 111.76 0)
			(effects
				(font
					(size 1.27 1.27)
					(thickness 0.15)
				)
				(justify left bottom)
				(hide yes)
			)
		)
		(property "Footprint" "antmicro-footprints:SOT-523"
			(at 245.11 114.3 0)
			(effects
				(font
					(size 1.27 1.27)
					(thickness 0.15)
				)
				(justify left bottom)
				(hide yes)
			)
		)
		(property "Datasheet" "https://www.mouser.com/datasheet/2/1057/PJE138K-1876698.pdf"
			(at 245.11 116.84 0)
			(effects
				(font
					(size 1.27 1.27)
					(thickness 0.15)
				)
				(justify left bottom)
				(hide yes)
			)
		)
		(property "Description" ""
			(at 222.25 102.87 0)
			(effects
				(font
					(size 1.27 1.27)
				)
				(hide yes)
			)
		)
		(property "MPN" "PJE138K_R1_00001"
			(at 231.14 101.6 0)
			(effects
				(font
					(size 1.27 1.27)
					(thickness 0.15)
				)
				(justify left)
			)
		)
		(property "Manufacturer" "PANJIT"
			(at 245.11 121.92 0)
			(effects
				(font
					(size 1.27 1.27)
					(thickness 0.15)
				)
				(justify left bottom)
				(hide yes)
			)
		)
		(property "Author" "Antmicro"
			(at 245.11 124.46 0)
			(effects
				(font
					(size 1.27 1.27)
					(thickness 0.15)
				)
				(justify left bottom)
				(hide yes)
			)
		)
		(property "License" "Apache-2.0"
			(at 245.11 127 0)
			(effects
				(font
					(size 1.27 1.27)
					(thickness 0.15)
				)
				(justify left bottom)
				(hide yes)
			)
		)
		(pin "2"
		)
		(pin "3"
		)
		(pin "1"
		)
		(instances
			(project "jetson-orin-baseboard"
				(path ""
					(reference "Q4")
					(unit 1)
				)
			)
		)
	)
	(symbol
		(lib_name "+5V_3")
		(lib_id "antmicropower:+5V")
		(at 151.13 100.33 0)
		(mirror y)
		(unit 1)
		(exclude_from_sim no)
		(in_bom yes)
		(on_board yes)
		(dnp no)
		(property "Reference" "#PWR0113"
			(at 151.13 104.14 0)
			(effects
				(font
					(size 1.27 1.27)
				)
				(justify left bottom)
				(hide yes)
			)
		)
		(property "Value" "+5V"
			(at 148.59 96.52 0)
			(effects
				(font
					(size 1.27 1.27)
					(thickness 0.15)
				)
				(justify right)
			)
		)
		(property "Footprint" ""
			(at 135.89 107.95 0)
			(effects
				(font
					(size 1.27 1.27)
					(thickness 0.15)
				)
				(justify left bottom)
				(hide yes)
			)
		)
		(property "Datasheet" ""
			(at 135.89 110.49 0)
			(effects
				(font
					(size 1.27 1.27)
					(thickness 0.15)
				)
				(justify left bottom)
				(hide yes)
			)
		)
		(property "Description" ""
			(at 151.13 100.33 0)
			(effects
				(font
					(size 1.27 1.27)
				)
				(hide yes)
			)
		)
		(property "Author" "Antmicro"
			(at 135.89 107.95 0)
			(effects
				(font
					(size 1.27 1.27)
					(thickness 0.15)
				)
				(justify left bottom)
				(hide yes)
			)
		)
		(property "License" "Apache-2.0"
			(at 135.89 110.49 0)
			(effects
				(font
					(size 1.27 1.27)
					(thickness 0.15)
				)
				(justify left bottom)
				(hide yes)
			)
		)
		(pin "1"
		)
		(instances
			(project "jetson-orin-baseboard"
				(path ""
					(reference "#PWR0113")
					(unit 1)
				)
			)
		)
	)
	(symbol
		(lib_id "antmicroCapacitors0402:C_100n_0402")
		(at 226.06 76.2 90)
		(mirror x)
		(unit 1)
		(exclude_from_sim no)
		(in_bom yes)
		(on_board yes)
		(dnp no)
		(fields_autoplaced yes)
		(property "Reference" "C73"
			(at 228.6 77.4763 90)
			(effects
				(font
					(size 1.27 1.27)
				)
				(justify right)
			)
		)
		(property "Value" "C_100n_0402"
			(at 236.22 96.52 0)
			(effects
				(font
					(size 1.27 1.27)
					(thickness 0.15)
				)
				(justify left bottom)
				(hide yes)
			)
		)
		(property "Footprint" "antmicro-footprints:C_0402_1005Metric"
			(at 238.76 96.52 0)
			(effects
				(font
					(size 1.27 1.27)
					(thickness 0.15)
				)
				(justify left bottom)
				(hide yes)
			)
		)
		(property "Datasheet" "https://www.murata.com/products/productdetail?partno=GRM155R61H104KE14%23"
			(at 241.3 96.52 0)
			(effects
				(font
					(size 1.27 1.27)
					(thickness 0.15)
				)
				(justify left bottom)
				(hide yes)
			)
		)
		(property "Description" ""
			(at 226.06 76.2 0)
			(effects
				(font
					(size 1.27 1.27)
				)
				(hide yes)
			)
		)
		(property "Manufacturer" "Murata"
			(at 246.38 96.52 0)
			(effects
				(font
					(size 1.27 1.27)
					(thickness 0.15)
				)
				(justify left bottom)
				(hide yes)
			)
		)
		(property "MPN" "GRM155R61H104KE14D"
			(at 243.84 96.52 0)
			(effects
				(font
					(size 1.27 1.27)
					(thickness 0.15)
				)
				(justify left bottom)
				(hide yes)
			)
		)
		(property "Val" "100n"
			(at 228.6 80.0163 90)
			(effects
				(font
					(size 1.27 1.27)
					(thickness 0.15)
				)
				(justify right)
			)
		)
		(property "License" "Apache-2.0"
			(at 248.92 96.52 0)
			(effects
				(font
					(size 1.27 1.27)
					(thickness 0.15)
				)
				(justify left bottom)
				(hide yes)
			)
		)
		(property "Author" "Antmicro"
			(at 251.46 96.52 0)
			(effects
				(font
					(size 1.27 1.27)
					(thickness 0.15)
				)
				(justify left bottom)
				(hide yes)
			)
		)
		(property "Voltage" "50V"
			(at 254 96.52 0)
			(effects
				(font
					(size 1.27 1.27)
				)
				(justify left bottom)
				(hide yes)
			)
		)
		(property "Dielectric" "X5R"
			(at 256.54 96.52 0)
			(effects
				(font
					(size 1.27 1.27)
				)
				(justify left bottom)
				(hide yes)
			)
		)
		(pin "1"
		)
		(pin "2"
		)
		(instances
			(project "jetson-orin-baseboard"
				(path ""
					(reference "C73")
					(unit 1)
				)
			)
		)
	)
	(symbol
		(lib_id "antmicroResistors0402:R_10k_0402")
		(at 207.01 95.25 270)
		(unit 1)
		(exclude_from_sim no)
		(in_bom yes)
		(on_board yes)
		(dnp no)
		(property "Reference" "R136"
			(at 208.28 96.52 90)
			(effects
				(font
					(size 1.27 1.27)
				)
				(justify left)
			)
		)
		(property "Value" "R_10k_0402"
			(at 194.31 115.57 0)
			(effects
				(font
					(size 1.27 1.27)
					(thickness 0.15)
				)
				(justify left bottom)
				(hide yes)
			)
		)
		(property "Footprint" "antmicro-footprints:R_0402_1005Metric"
			(at 191.77 115.57 0)
			(effects
				(font
					(size 1.27 1.27)
					(thickness 0.15)
				)
				(justify left bottom)
				(hide yes)
			)
		)
		(property "Datasheet" "https://www.bourns.com/docs/product-datasheets/cr.pdf"
			(at 189.23 115.57 0)
			(effects
				(font
					(size 1.27 1.27)
					(thickness 0.15)
				)
				(justify left bottom)
				(hide yes)
			)
		)
		(property "Description" ""
			(at 207.01 95.25 0)
			(effects
				(font
					(size 1.27 1.27)
				)
				(hide yes)
			)
		)
		(property "Manufacturer" "Bourns"
			(at 184.15 115.57 0)
			(effects
				(font
					(size 1.27 1.27)
					(thickness 0.15)
				)
				(justify left bottom)
				(hide yes)
			)
		)
		(property "MPN" "CR0402-FX-1002GLF"
			(at 186.69 115.57 0)
			(effects
				(font
					(size 1.27 1.27)
					(thickness 0.15)
				)
				(justify left bottom)
				(hide yes)
			)
		)
		(property "Val" "10k"
			(at 208.28 99.06 90)
			(effects
				(font
					(size 1.27 1.27)
					(thickness 0.15)
				)
				(justify left)
			)
		)
		(property "License" "Apache-2.0"
			(at 181.61 115.57 0)
			(effects
				(font
					(size 1.27 1.27)
					(thickness 0.15)
				)
				(justify left bottom)
				(hide yes)
			)
		)
		(property "Author" "Antmicro"
			(at 179.07 115.57 0)
			(effects
				(font
					(size 1.27 1.27)
					(thickness 0.15)
				)
				(justify left bottom)
				(hide yes)
			)
		)
		(property "Tolerance" "1%"
			(at 196.85 115.57 0)
			(effects
				(font
					(size 1.27 1.27)
				)
				(justify left bottom)
				(hide yes)
			)
		)
		(pin "1"
		)
		(pin "2"
		)
		(instances
			(project "jetson-orin-baseboard"
				(path ""
					(reference "R136")
					(unit 1)
				)
			)
		)
	)
	(symbol
		(lib_id "antmicroCapacitors0402:C_100n_0402")
		(at 207.01 162.56 180)
		(unit 1)
		(exclude_from_sim no)
		(in_bom yes)
		(on_board yes)
		(dnp no)
		(property "Reference" "C70"
			(at 209.55 160.655 0)
			(effects
				(font
					(size 1.27 1.27)
				)
				(justify left bottom)
			)
		)
		(property "Value" "C_100n_0402"
			(at 186.69 152.4 0)
			(effects
				(font
					(size 1.27 1.27)
					(thickness 0.15)
				)
				(justify left bottom)
				(hide yes)
			)
		)
		(property "Footprint" "antmicro-footprints:C_0402_1005Metric"
			(at 186.69 149.86 0)
			(effects
				(font
					(size 1.27 1.27)
					(thickness 0.15)
				)
				(justify left bottom)
				(hide yes)
			)
		)
		(property "Datasheet" "https://www.murata.com/products/productdetail?partno=GRM155R61H104KE14%23"
			(at 186.69 147.32 0)
			(effects
				(font
					(size 1.27 1.27)
					(thickness 0.15)
				)
				(justify left bottom)
				(hide yes)
			)
		)
		(property "Description" ""
			(at 207.01 162.56 0)
			(effects
				(font
					(size 1.27 1.27)
				)
				(hide yes)
			)
		)
		(property "Manufacturer" "Murata"
			(at 186.69 142.24 0)
			(effects
				(font
					(size 1.27 1.27)
					(thickness 0.15)
				)
				(justify left bottom)
				(hide yes)
			)
		)
		(property "MPN" "GRM155R61H104KE14D"
			(at 186.69 144.78 0)
			(effects
				(font
					(size 1.27 1.27)
					(thickness 0.15)
				)
				(justify left bottom)
				(hide yes)
			)
		)
		(property "Val" "100n"
			(at 203.2 163.195 0)
			(effects
				(font
					(size 1.27 1.27)
					(thickness 0.15)
				)
				(justify left bottom)
			)
		)
		(property "License" "Apache-2.0"
			(at 186.69 139.7 0)
			(effects
				(font
					(size 1.27 1.27)
					(thickness 0.15)
				)
				(justify left bottom)
				(hide yes)
			)
		)
		(property "Author" "Antmicro"
			(at 186.69 137.16 0)
			(effects
				(font
					(size 1.27 1.27)
					(thickness 0.15)
				)
				(justify left bottom)
				(hide yes)
			)
		)
		(property "Voltage" "50V"
			(at 186.69 134.62 0)
			(effects
				(font
					(size 1.27 1.27)
				)
				(justify left bottom)
				(hide yes)
			)
		)
		(property "Dielectric" "X5R"
			(at 186.69 132.08 0)
			(effects
				(font
					(size 1.27 1.27)
				)
				(justify left bottom)
				(hide yes)
			)
		)
		(pin "1"
		)
		(pin "2"
		)
		(instances
			(project "jetson-orin-baseboard"
				(path ""
					(reference "C70")
					(unit 1)
				)
			)
		)
	)
	(symbol
		(lib_name "GND_3")
		(lib_id "antmicropower:GND")
		(at 254 99.06 0)
		(unit 1)
		(exclude_from_sim no)
		(in_bom yes)
		(on_board yes)
		(dnp no)
		(property "Reference" "#PWR0125"
			(at 254 105.41 0)
			(effects
				(font
					(size 1.27 1.27)
				)
				(justify left bottom)
				(hide yes)
			)
		)
		(property "Value" "GND"
			(at 254 102.87 0)
			(effects
				(font
					(size 1.27 1.27)
					(thickness 0.15)
				)
			)
		)
		(property "Footprint" ""
			(at 262.89 106.68 0)
			(effects
				(font
					(size 1.27 1.27)
					(thickness 0.15)
				)
				(justify left bottom)
				(hide yes)
			)
		)
		(property "Datasheet" ""
			(at 262.89 111.76 0)
			(effects
				(font
					(size 1.27 1.27)
					(thickness 0.15)
				)
				(justify left bottom)
				(hide yes)
			)
		)
		(property "Description" ""
			(at 254 99.06 0)
			(effects
				(font
					(size 1.27 1.27)
				)
				(hide yes)
			)
		)
		(property "Author" "Antmicro"
			(at 262.89 106.68 0)
			(effects
				(font
					(size 1.27 1.27)
					(thickness 0.15)
				)
				(justify left bottom)
				(hide yes)
			)
		)
		(property "License" "Apache-2.0"
			(at 262.89 109.22 0)
			(effects
				(font
					(size 1.27 1.27)
					(thickness 0.15)
				)
				(justify left bottom)
				(hide yes)
			)
		)
		(pin "1"
		)
		(instances
			(project "jetson-orin-baseboard"
				(path ""
					(reference "#PWR0125")
					(unit 1)
				)
			)
		)
	)
	(symbol
		(lib_name "R_0R_0402_11")
		(lib_id "antmicroResistors0402:R_0R_0402")
		(at 119.38 172.72 0)
		(unit 1)
		(exclude_from_sim no)
		(in_bom no)
		(on_board yes)
		(dnp yes)
		(property "Reference" "R124"
			(at 124.46 172.085 0)
			(effects
				(font
					(size 1.27 1.27)
				)
				(justify left bottom)
			)
		)
		(property "Value" "R_0R_0402"
			(at 139.7 185.42 0)
			(effects
				(font
					(size 1.27 1.27)
					(thickness 0.15)
				)
				(justify left bottom)
				(hide yes)
			)
		)
		(property "Footprint" "antmicro-footprints:R_0402_1005Metric"
			(at 139.7 187.96 0)
			(effects
				(font
					(size 1.27 1.27)
					(thickness 0.15)
				)
				(justify left bottom)
				(hide yes)
			)
		)
		(property "Datasheet" "https://industrial.panasonic.com/cdbs/www-data/pdf/RDA0000/AOA0000C301.pdf"
			(at 139.7 190.5 0)
			(effects
				(font
					(size 1.27 1.27)
					(thickness 0.15)
				)
				(justify left bottom)
				(hide yes)
			)
		)
		(property "Description" ""
			(at 119.38 172.72 0)
			(effects
				(font
					(size 1.27 1.27)
				)
				(hide yes)
			)
		)
		(property "Manufacturer" "Panasonic"
			(at 139.7 195.58 0)
			(effects
				(font
					(size 1.27 1.27)
					(thickness 0.15)
				)
				(justify left bottom)
				(hide yes)
			)
		)
		(property "MPN" "ERJ2GE0R00X"
			(at 139.7 193.04 0)
			(effects
				(font
					(size 1.27 1.27)
					(thickness 0.15)
				)
				(justify left bottom)
				(hide yes)
			)
		)
		(property "Val" "0R"
			(at 116.84 172.085 0)
			(effects
				(font
					(size 1.27 1.27)
					(thickness 0.15)
				)
				(justify left bottom)
			)
		)
		(property "License" "Apache-2.0"
			(at 139.7 198.12 0)
			(effects
				(font
					(size 1.27 1.27)
					(thickness 0.15)
				)
				(justify left bottom)
				(hide yes)
			)
		)
		(property "Author" "Antmicro"
			(at 139.7 200.66 0)
			(effects
				(font
					(size 1.27 1.27)
					(thickness 0.15)
				)
				(justify left bottom)
				(hide yes)
			)
		)
		(property "Tolerance" "~"
			(at 139.7 182.88 0)
			(effects
				(font
					(size 1.27 1.27)
				)
				(justify left bottom)
				(hide yes)
			)
		)
		(property "Current" "1A"
			(at 139.7 203.2 0)
			(effects
				(font
					(size 1.27 1.27)
					(thickness 0.15)
				)
				(justify left bottom)
				(hide yes)
			)
		)
		(pin "1"
		)
		(pin "2"
		)
		(instances
			(project "jetson-orin-baseboard"
				(path ""
					(reference "R124")
					(unit 1)
				)
			)
		)
	)
	(symbol
		(lib_name "+3V3_2")
		(lib_id "antmicropower:+3V3")
		(at 129.54 100.33 0)
		(mirror y)
		(unit 1)
		(exclude_from_sim no)
		(in_bom yes)
		(on_board yes)
		(dnp no)
		(property "Reference" "#PWR0118"
			(at 129.54 104.14 0)
			(effects
				(font
					(size 1.27 1.27)
				)
				(justify left bottom)
				(hide yes)
			)
		)
		(property "Value" "+3V3"
			(at 126.365 96.52 0)
			(effects
				(font
					(size 1.27 1.27)
					(thickness 0.15)
				)
				(justify right)
			)
		)
		(property "Footprint" ""
			(at 114.3 107.95 0)
			(effects
				(font
					(size 1.27 1.27)
					(thickness 0.15)
				)
				(justify left bottom)
				(hide yes)
			)
		)
		(property "Datasheet" ""
			(at 114.3 110.49 0)
			(effects
				(font
					(size 1.27 1.27)
					(thickness 0.15)
				)
				(justify left bottom)
				(hide yes)
			)
		)
		(property "Description" ""
			(at 129.54 100.33 0)
			(effects
				(font
					(size 1.27 1.27)
				)
				(hide yes)
			)
		)
		(property "Author" "Antmicro"
			(at 114.3 102.87 0)
			(effects
				(font
					(size 1.27 1.27)
					(thickness 0.15)
				)
				(justify left bottom)
				(hide yes)
			)
		)
		(property "License" "Apache-2.0"
			(at 114.3 105.41 0)
			(effects
				(font
					(size 1.27 1.27)
					(thickness 0.15)
				)
				(justify left bottom)
				(hide yes)
			)
		)
		(pin "1"
		)
		(instances
			(project "jetson-orin-baseboard"
				(path ""
					(reference "#PWR0118")
					(unit 1)
				)
			)
		)
	)
	(symbol
		(lib_name "R_10k_0402_2")
		(lib_id "antmicroResistors0402:R_10k_0402")
		(at 113.03 127 270)
		(unit 1)
		(exclude_from_sim no)
		(in_bom no)
		(on_board yes)
		(dnp yes)
		(property "Reference" "R115"
			(at 114.3 128.27 90)
			(effects
				(font
					(size 1.27 1.27)
				)
				(justify left)
			)
		)
		(property "Value" "R_10k_0402"
			(at 100.33 147.32 0)
			(effects
				(font
					(size 1.27 1.27)
					(thickness 0.15)
				)
				(justify left bottom)
				(hide yes)
			)
		)
		(property "Footprint" "antmicro-footprints:R_0402_1005Metric"
			(at 97.79 147.32 0)
			(effects
				(font
					(size 1.27 1.27)
					(thickness 0.15)
				)
				(justify left bottom)
				(hide yes)
			)
		)
		(property "Datasheet" "https://www.bourns.com/docs/product-datasheets/cr.pdf"
			(at 95.25 147.32 0)
			(effects
				(font
					(size 1.27 1.27)
					(thickness 0.15)
				)
				(justify left bottom)
				(hide yes)
			)
		)
		(property "Description" ""
			(at 113.03 127 0)
			(effects
				(font
					(size 1.27 1.27)
				)
				(hide yes)
			)
		)
		(property "Manufacturer" "Bourns"
			(at 90.17 147.32 0)
			(effects
				(font
					(size 1.27 1.27)
					(thickness 0.15)
				)
				(justify left bottom)
				(hide yes)
			)
		)
		(property "MPN" "CR0402-FX-1002GLF"
			(at 92.71 147.32 0)
			(effects
				(font
					(size 1.27 1.27)
					(thickness 0.15)
				)
				(justify left bottom)
				(hide yes)
			)
		)
		(property "Val" "10k"
			(at 114.3 130.81 90)
			(effects
				(font
					(size 1.27 1.27)
					(thickness 0.15)
				)
				(justify left)
			)
		)
		(property "License" "Apache-2.0"
			(at 87.63 147.32 0)
			(effects
				(font
					(size 1.27 1.27)
					(thickness 0.15)
				)
				(justify left bottom)
				(hide yes)
			)
		)
		(property "Author" "Antmicro"
			(at 85.09 147.32 0)
			(effects
				(font
					(size 1.27 1.27)
					(thickness 0.15)
				)
				(justify left bottom)
				(hide yes)
			)
		)
		(property "Tolerance" "1%"
			(at 102.87 147.32 0)
			(effects
				(font
					(size 1.27 1.27)
				)
				(justify left bottom)
				(hide yes)
			)
		)
		(pin "1"
		)
		(pin "2"
		)
		(instances
			(project "jetson-orin-baseboard"
				(path ""
					(reference "R115")
					(unit 1)
				)
			)
		)
	)
	(symbol
		(lib_id "antmicroTestPoints:TP_0.75mm_SMD")
		(at 287.02 85.09 90)
		(unit 1)
		(exclude_from_sim no)
		(in_bom no)
		(on_board yes)
		(dnp no)
		(property "Reference" "TP29"
			(at 287.02 81.28 0)
			(effects
				(font
					(size 1.27 1.27)
				)
				(justify left)
			)
		)
		(property "Value" "TP_0.75mm_SMD"
			(at 290.83 74.93 0)
			(effects
				(font
					(size 1.27 1.27)
					(thickness 0.15)
				)
				(justify left bottom)
				(hide yes)
			)
		)
		(property "Footprint" "antmicro-footprints:TP_SMD_0.75mm"
			(at 293.37 74.93 0)
			(effects
				(font
					(size 1.27 1.27)
					(thickness 0.15)
				)
				(justify left bottom)
				(hide yes)
			)
		)
		(property "Datasheet" ""
			(at 299.72 67.31 0)
			(effects
				(font
					(size 1.27 1.27)
					(thickness 0.15)
				)
				(justify left bottom)
				(hide yes)
			)
		)
		(property "Description" ""
			(at 287.02 85.09 0)
			(effects
				(font
					(size 1.27 1.27)
				)
				(hide yes)
			)
		)
		(property "MPN" ""
			(at 298.45 74.295 0)
			(effects
				(font
					(size 1.27 1.27)
					(thickness 0.15)
				)
				(justify left bottom)
				(hide yes)
			)
		)
		(property "Manufacturer" ""
			(at 293.37 74.295 0)
			(effects
				(font
					(size 1.27 1.27)
					(thickness 0.15)
				)
				(justify left bottom)
				(hide yes)
			)
		)
		(property "Author" "Antmicro"
			(at 295.91 74.93 0)
			(effects
				(font
					(size 1.27 1.27)
					(thickness 0.15)
				)
				(justify left bottom)
				(hide yes)
			)
		)
		(property "License" "Apache-2.0"
			(at 298.45 74.93 0)
			(effects
				(font
					(size 1.27 1.27)
					(thickness 0.15)
				)
				(justify left bottom)
				(hide yes)
			)
		)
		(pin "1"
		)
		(instances
			(project "jetson-orin-baseboard"
				(path ""
					(reference "TP29")
					(unit 1)
				)
			)
		)
	)
)
